FILE_TYPE = MACRO_DRAWING;
SET COLOR_WIRE YELLOW;
SET COLOR_PROP MONO;
SET COLOR_DOT WHITE;
SET COLOR_ARC YELLOW;
SET COLOR_BODY GREEN;
SET COLOR_NOTE MONO;
SET PROP_DISPLAY VALUE;
SET PAGE_NUMBER P60;
FORCEADD OFFPAGE..5
(-6425 525);
FORCEPROP 2 LAST $XR0 83 
J 0
(-6679 525);
DISPLAY 0.638298 (-6679 525);
PAINT MONO (-6679 525);
FORCEPROP 2 LAST $XR1 84 
J 0
(-6769 525);
DISPLAY 0.638298 (-6769 525);
PAINT MONO (-6769 525);
FORCEPROP 2 LAST CDS_LIB mstr_standard
J 0
(-6425 525);
PAINT MONO (-6425 525);
DISPLAY INVISIBLE (-6425 525);
FORCEPROP 1 LAST OFFPAGE TRUE
J 0
(-6100 400);
DISPLAY 1.170213 (-6100 400);
PAINT GREEN (-6100 400);
DISPLAY INVISIBLE (-6100 400);
FORCEPROP 1 LAST COMMENT_BODY TRUE
J 0
(-6325 450);
DISPLAY 1.170213 (-6325 450);
PAINT GREEN (-6325 450);
DISPLAY INVISIBLE (-6325 450);
FORCEPROP 2 LAST PATH I1
J 0
(-6375 600);
DISPLAY 1.021277 (-6375 600);
PAINT ORANGE (-6375 600);
DISPLAY INVISIBLE (-6375 600);
FORCEADD TAP..6
(-5575 825);
FORCEPROP 3 LASTPIN (-5525 825) SIG_NAME M_K_CLK_DP<0>
J 0
(-5515 835);
DISPLAY 0.659574 (-5515 835);
PAINT MONO (-5515 835);
DISPLAY INVISIBLE (-5515 835);
FORCEPROP 1 LASTPIN (-5525 825) BN 0
J 0
(-5577 833);
DISPLAY 0.617021 (-5577 833);
PAINT GREEN (-5577 833);
FORCEPROP 2 LAST CDS_LIB mstr_standard
J 0
(-5575 825);
PAINT MONO (-5575 825);
DISPLAY INVISIBLE (-5575 825);
FORCEPROP 1 LAST BODY_TYPE PLUMBING
J 0
(-5575 775);
DISPLAY 1.595745 (-5575 775);
PAINT GREEN (-5575 775);
DISPLAY INVISIBLE (-5575 775);
FORCEPROP 1 LAST HDL_TAP TRUE
J 0
(-5250 700);
DISPLAY 1.595745 (-5250 700);
PAINT GREEN (-5250 700);
DISPLAY INVISIBLE (-5250 700);
FORCEPROP 1 LAST PATH I10
J 0
(-5577 825);
DISPLAY 0.872340 (-5577 825);
PAINT GREEN (-5577 825);
DISPLAY INVISIBLE (-5577 825);
FORCEADD TAP..6
R 2
(-2850 1575);
FORCEPROP 3 LASTPIN (-2900 1575) SIG_NAME M_K_ODT<3>
J 0
(-2890 1585);
DISPLAY 0.659574 (-2890 1585);
PAINT MONO (-2890 1585);
DISPLAY INVISIBLE (-2890 1585);
FORCEPROP 1 LASTPIN (-2900 1575) BN 3
J 2
(-2848 1583);
DISPLAY 0.617021 (-2848 1583);
PAINT GREEN (-2848 1583);
FORCEPROP 2 LAST CDS_LIB mstr_standard
J 0
(-2850 1575);
PAINT MONO (-2850 1575);
DISPLAY INVISIBLE (-2850 1575);
FORCEPROP 1 LAST BODY_TYPE PLUMBING
J 2
(-2850 1525);
DISPLAY 1.595745 (-2850 1525);
PAINT GREEN (-2850 1525);
DISPLAY INVISIBLE (-2850 1525);
FORCEPROP 1 LAST HDL_TAP TRUE
J 2
(-3175 1450);
DISPLAY 1.595745 (-3175 1450);
PAINT GREEN (-3175 1450);
DISPLAY INVISIBLE (-3175 1450);
FORCEPROP 1 LAST PATH I100
J 2
(-2848 1575);
DISPLAY 0.872340 (-2848 1575);
PAINT GREEN (-2848 1575);
DISPLAY INVISIBLE (-2848 1575);
FORCEADD TAP..6
R 2
(-2850 1525);
FORCEPROP 3 LASTPIN (-2900 1525) SIG_NAME M_K_ODT<2>
J 0
(-2890 1535);
DISPLAY 0.659574 (-2890 1535);
PAINT MONO (-2890 1535);
DISPLAY INVISIBLE (-2890 1535);
FORCEPROP 1 LASTPIN (-2900 1525) BN 2
J 2
(-2848 1533);
DISPLAY 0.617021 (-2848 1533);
PAINT GREEN (-2848 1533);
FORCEPROP 2 LAST CDS_LIB mstr_standard
J 0
(-2850 1525);
PAINT MONO (-2850 1525);
DISPLAY INVISIBLE (-2850 1525);
FORCEPROP 1 LAST BODY_TYPE PLUMBING
J 2
(-2850 1475);
DISPLAY 1.595745 (-2850 1475);
PAINT GREEN (-2850 1475);
DISPLAY INVISIBLE (-2850 1475);
FORCEPROP 1 LAST HDL_TAP TRUE
J 2
(-3175 1400);
DISPLAY 1.595745 (-3175 1400);
PAINT GREEN (-3175 1400);
DISPLAY INVISIBLE (-3175 1400);
FORCEPROP 1 LAST PATH I101
J 2
(-2848 1525);
DISPLAY 0.872340 (-2848 1525);
PAINT GREEN (-2848 1525);
DISPLAY INVISIBLE (-2848 1525);
FORCEADD TAP..6
R 2
(-2850 1475);
FORCEPROP 3 LASTPIN (-2900 1475) SIG_NAME M_K_ODT<1>
J 0
(-2890 1485);
DISPLAY 0.659574 (-2890 1485);
PAINT MONO (-2890 1485);
DISPLAY INVISIBLE (-2890 1485);
FORCEPROP 1 LASTPIN (-2900 1475) BN 1
J 2
(-2848 1483);
DISPLAY 0.617021 (-2848 1483);
PAINT GREEN (-2848 1483);
FORCEPROP 2 LAST CDS_LIB mstr_standard
J 0
(-2850 1475);
PAINT MONO (-2850 1475);
DISPLAY INVISIBLE (-2850 1475);
FORCEPROP 1 LAST BODY_TYPE PLUMBING
J 2
(-2850 1425);
DISPLAY 1.595745 (-2850 1425);
PAINT GREEN (-2850 1425);
DISPLAY INVISIBLE (-2850 1425);
FORCEPROP 1 LAST HDL_TAP TRUE
J 2
(-3175 1350);
DISPLAY 1.595745 (-3175 1350);
PAINT GREEN (-3175 1350);
DISPLAY INVISIBLE (-3175 1350);
FORCEPROP 1 LAST PATH I102
J 2
(-2848 1475);
DISPLAY 0.872340 (-2848 1475);
PAINT GREEN (-2848 1475);
DISPLAY INVISIBLE (-2848 1475);
FORCEADD TAP..6
R 2
(-2850 1675);
FORCEPROP 3 LASTPIN (-2900 1675) SIG_NAME M_K_CKE<0>
J 0
(-2890 1685);
DISPLAY 0.659574 (-2890 1685);
PAINT MONO (-2890 1685);
DISPLAY INVISIBLE (-2890 1685);
FORCEPROP 1 LASTPIN (-2900 1675) BN 0
J 2
(-2848 1683);
DISPLAY 0.617021 (-2848 1683);
PAINT GREEN (-2848 1683);
FORCEPROP 2 LAST CDS_LIB mstr_standard
J 0
(-2850 1675);
PAINT MONO (-2850 1675);
DISPLAY INVISIBLE (-2850 1675);
FORCEPROP 1 LAST BODY_TYPE PLUMBING
J 2
(-2850 1625);
DISPLAY 1.595745 (-2850 1625);
PAINT GREEN (-2850 1625);
DISPLAY INVISIBLE (-2850 1625);
FORCEPROP 1 LAST HDL_TAP TRUE
J 2
(-3175 1550);
DISPLAY 1.595745 (-3175 1550);
PAINT GREEN (-3175 1550);
DISPLAY INVISIBLE (-3175 1550);
FORCEPROP 1 LAST PATH I103
J 2
(-2848 1675);
DISPLAY 0.872340 (-2848 1675);
PAINT GREEN (-2848 1675);
DISPLAY INVISIBLE (-2848 1675);
FORCEADD TAP..6
R 2
(-2850 1725);
FORCEPROP 3 LASTPIN (-2900 1725) SIG_NAME M_K_CKE<1>
J 0
(-2890 1735);
DISPLAY 0.659574 (-2890 1735);
PAINT MONO (-2890 1735);
DISPLAY INVISIBLE (-2890 1735);
FORCEPROP 1 LASTPIN (-2900 1725) BN 1
J 2
(-2848 1733);
DISPLAY 0.617021 (-2848 1733);
PAINT GREEN (-2848 1733);
FORCEPROP 2 LAST CDS_LIB mstr_standard
J 0
(-2850 1725);
PAINT MONO (-2850 1725);
DISPLAY INVISIBLE (-2850 1725);
FORCEPROP 1 LAST BODY_TYPE PLUMBING
J 2
(-2850 1675);
DISPLAY 1.595745 (-2850 1675);
PAINT GREEN (-2850 1675);
DISPLAY INVISIBLE (-2850 1675);
FORCEPROP 1 LAST HDL_TAP TRUE
J 2
(-3175 1600);
DISPLAY 1.595745 (-3175 1600);
PAINT GREEN (-3175 1600);
DISPLAY INVISIBLE (-3175 1600);
FORCEPROP 1 LAST PATH I104
J 2
(-2848 1725);
DISPLAY 0.872340 (-2848 1725);
PAINT GREEN (-2848 1725);
DISPLAY INVISIBLE (-2848 1725);
FORCEADD TAP..6
R 2
(-2850 1775);
FORCEPROP 3 LASTPIN (-2900 1775) SIG_NAME M_K_CKE<2>
J 0
(-2890 1785);
DISPLAY 0.659574 (-2890 1785);
PAINT MONO (-2890 1785);
DISPLAY INVISIBLE (-2890 1785);
FORCEPROP 1 LASTPIN (-2900 1775) BN 2
J 2
(-2848 1783);
DISPLAY 0.617021 (-2848 1783);
PAINT GREEN (-2848 1783);
FORCEPROP 2 LAST CDS_LIB mstr_standard
J 0
(-2850 1775);
PAINT MONO (-2850 1775);
DISPLAY INVISIBLE (-2850 1775);
FORCEPROP 1 LAST BODY_TYPE PLUMBING
J 2
(-2850 1725);
DISPLAY 1.595745 (-2850 1725);
PAINT GREEN (-2850 1725);
DISPLAY INVISIBLE (-2850 1725);
FORCEPROP 1 LAST HDL_TAP TRUE
J 2
(-3175 1650);
DISPLAY 1.595745 (-3175 1650);
PAINT GREEN (-3175 1650);
DISPLAY INVISIBLE (-3175 1650);
FORCEPROP 1 LAST PATH I105
J 2
(-2848 1775);
DISPLAY 0.872340 (-2848 1775);
PAINT GREEN (-2848 1775);
DISPLAY INVISIBLE (-2848 1775);
FORCEADD TAP..6
R 2
(-2850 1825);
FORCEPROP 3 LASTPIN (-2900 1825) SIG_NAME M_K_CKE<3>
J 0
(-2890 1835);
DISPLAY 0.659574 (-2890 1835);
PAINT MONO (-2890 1835);
DISPLAY INVISIBLE (-2890 1835);
FORCEPROP 1 LASTPIN (-2900 1825) BN 3
J 2
(-2848 1833);
DISPLAY 0.617021 (-2848 1833);
PAINT GREEN (-2848 1833);
FORCEPROP 2 LAST CDS_LIB mstr_standard
J 0
(-2850 1825);
PAINT MONO (-2850 1825);
DISPLAY INVISIBLE (-2850 1825);
FORCEPROP 1 LAST BODY_TYPE PLUMBING
J 2
(-2850 1775);
DISPLAY 1.595745 (-2850 1775);
PAINT GREEN (-2850 1775);
DISPLAY INVISIBLE (-2850 1775);
FORCEPROP 1 LAST HDL_TAP TRUE
J 2
(-3175 1700);
DISPLAY 1.595745 (-3175 1700);
PAINT GREEN (-3175 1700);
DISPLAY INVISIBLE (-3175 1700);
FORCEPROP 1 LAST PATH I106
J 2
(-2848 1825);
DISPLAY 0.872340 (-2848 1825);
PAINT GREEN (-2848 1825);
DISPLAY INVISIBLE (-2848 1825);
FORCEADD TAP..6
R 2
(-2850 1925);
FORCEPROP 3 LASTPIN (-2900 1925) SIG_NAME M_K_MA<0>
J 0
(-2890 1935);
DISPLAY 0.659574 (-2890 1935);
PAINT MONO (-2890 1935);
DISPLAY INVISIBLE (-2890 1935);
FORCEPROP 1 LASTPIN (-2900 1925) BN 0
J 2
(-2848 1933);
DISPLAY 0.617021 (-2848 1933);
PAINT GREEN (-2848 1933);
FORCEPROP 2 LAST CDS_LIB mstr_standard
J 0
(-2850 1925);
PAINT MONO (-2850 1925);
DISPLAY INVISIBLE (-2850 1925);
FORCEPROP 1 LAST BODY_TYPE PLUMBING
J 2
(-2850 1875);
DISPLAY 1.595745 (-2850 1875);
PAINT GREEN (-2850 1875);
DISPLAY INVISIBLE (-2850 1875);
FORCEPROP 1 LAST HDL_TAP TRUE
J 2
(-3175 1800);
DISPLAY 1.595745 (-3175 1800);
PAINT GREEN (-3175 1800);
DISPLAY INVISIBLE (-3175 1800);
FORCEPROP 1 LAST PATH I107
J 2
(-2848 1925);
DISPLAY 0.872340 (-2848 1925);
PAINT GREEN (-2848 1925);
DISPLAY INVISIBLE (-2848 1925);
FORCEADD TAP..6
R 2
(-2850 1975);
FORCEPROP 3 LASTPIN (-2900 1975) SIG_NAME M_K_MA<1>
J 0
(-2890 1985);
DISPLAY 0.659574 (-2890 1985);
PAINT MONO (-2890 1985);
DISPLAY INVISIBLE (-2890 1985);
FORCEPROP 1 LASTPIN (-2900 1975) BN 1
J 2
(-2848 1983);
DISPLAY 0.617021 (-2848 1983);
PAINT GREEN (-2848 1983);
FORCEPROP 2 LAST CDS_LIB mstr_standard
J 0
(-2850 1975);
PAINT MONO (-2850 1975);
DISPLAY INVISIBLE (-2850 1975);
FORCEPROP 1 LAST BODY_TYPE PLUMBING
J 2
(-2850 1925);
DISPLAY 1.595745 (-2850 1925);
PAINT GREEN (-2850 1925);
DISPLAY INVISIBLE (-2850 1925);
FORCEPROP 1 LAST HDL_TAP TRUE
J 2
(-3175 1850);
DISPLAY 1.595745 (-3175 1850);
PAINT GREEN (-3175 1850);
DISPLAY INVISIBLE (-3175 1850);
FORCEPROP 1 LAST PATH I108
J 2
(-2848 1975);
DISPLAY 0.872340 (-2848 1975);
PAINT GREEN (-2848 1975);
DISPLAY INVISIBLE (-2848 1975);
FORCEADD TAP..6
R 2
(-2850 2075);
FORCEPROP 3 LASTPIN (-2900 2075) SIG_NAME M_K_MA<3>
J 0
(-2890 2085);
DISPLAY 0.659574 (-2890 2085);
PAINT MONO (-2890 2085);
DISPLAY INVISIBLE (-2890 2085);
FORCEPROP 1 LASTPIN (-2900 2075) BN 3
J 2
(-2848 2083);
DISPLAY 0.617021 (-2848 2083);
PAINT GREEN (-2848 2083);
FORCEPROP 2 LAST CDS_LIB mstr_standard
J 0
(-2850 2075);
PAINT MONO (-2850 2075);
DISPLAY INVISIBLE (-2850 2075);
FORCEPROP 1 LAST BODY_TYPE PLUMBING
J 2
(-2850 2025);
DISPLAY 1.595745 (-2850 2025);
PAINT GREEN (-2850 2025);
DISPLAY INVISIBLE (-2850 2025);
FORCEPROP 1 LAST HDL_TAP TRUE
J 2
(-3175 1950);
DISPLAY 1.595745 (-3175 1950);
PAINT GREEN (-3175 1950);
DISPLAY INVISIBLE (-3175 1950);
FORCEPROP 1 LAST PATH I109
J 2
(-2848 2075);
DISPLAY 0.872340 (-2848 2075);
PAINT GREEN (-2848 2075);
DISPLAY INVISIBLE (-2848 2075);
FORCEADD TAP..6
(-5575 925);
FORCEPROP 3 LASTPIN (-5525 925) SIG_NAME M_K_CLK_DP<2>
J 0
(-5515 935);
DISPLAY 0.659574 (-5515 935);
PAINT MONO (-5515 935);
DISPLAY INVISIBLE (-5515 935);
FORCEPROP 1 LASTPIN (-5525 925) BN 2
J 0
(-5577 933);
DISPLAY 0.617021 (-5577 933);
PAINT GREEN (-5577 933);
FORCEPROP 2 LAST CDS_LIB mstr_standard
J 0
(-5575 925);
PAINT MONO (-5575 925);
DISPLAY INVISIBLE (-5575 925);
FORCEPROP 1 LAST BODY_TYPE PLUMBING
J 0
(-5575 875);
DISPLAY 1.595745 (-5575 875);
PAINT GREEN (-5575 875);
DISPLAY INVISIBLE (-5575 875);
FORCEPROP 1 LAST HDL_TAP TRUE
J 0
(-5250 800);
DISPLAY 1.595745 (-5250 800);
PAINT GREEN (-5250 800);
DISPLAY INVISIBLE (-5250 800);
FORCEPROP 1 LAST PATH I11
J 0
(-5577 925);
DISPLAY 0.872340 (-5577 925);
PAINT GREEN (-5577 925);
DISPLAY INVISIBLE (-5577 925);
FORCEADD TAP..6
R 2
(-2850 2025);
FORCEPROP 3 LASTPIN (-2900 2025) SIG_NAME M_K_MA<2>
J 0
(-2890 2035);
DISPLAY 0.659574 (-2890 2035);
PAINT MONO (-2890 2035);
DISPLAY INVISIBLE (-2890 2035);
FORCEPROP 1 LASTPIN (-2900 2025) BN 2
J 2
(-2848 2033);
DISPLAY 0.617021 (-2848 2033);
PAINT GREEN (-2848 2033);
FORCEPROP 2 LAST CDS_LIB mstr_standard
J 0
(-2850 2025);
PAINT MONO (-2850 2025);
DISPLAY INVISIBLE (-2850 2025);
FORCEPROP 1 LAST BODY_TYPE PLUMBING
J 2
(-2850 1975);
DISPLAY 1.595745 (-2850 1975);
PAINT GREEN (-2850 1975);
DISPLAY INVISIBLE (-2850 1975);
FORCEPROP 1 LAST HDL_TAP TRUE
J 2
(-3175 1900);
DISPLAY 1.595745 (-3175 1900);
PAINT GREEN (-3175 1900);
DISPLAY INVISIBLE (-3175 1900);
FORCEPROP 1 LAST PATH I110
J 2
(-2848 2025);
DISPLAY 0.872340 (-2848 2025);
PAINT GREEN (-2848 2025);
DISPLAY INVISIBLE (-2848 2025);
FORCEADD TAP..6
R 2
(-2850 2125);
FORCEPROP 3 LASTPIN (-2900 2125) SIG_NAME M_K_MA<4>
J 0
(-2890 2135);
DISPLAY 0.659574 (-2890 2135);
PAINT MONO (-2890 2135);
DISPLAY INVISIBLE (-2890 2135);
FORCEPROP 1 LASTPIN (-2900 2125) BN 4
J 2
(-2848 2133);
DISPLAY 0.617021 (-2848 2133);
PAINT GREEN (-2848 2133);
FORCEPROP 2 LAST CDS_LIB mstr_standard
J 0
(-2850 2125);
PAINT MONO (-2850 2125);
DISPLAY INVISIBLE (-2850 2125);
FORCEPROP 1 LAST BODY_TYPE PLUMBING
J 2
(-2850 2075);
DISPLAY 1.595745 (-2850 2075);
PAINT GREEN (-2850 2075);
DISPLAY INVISIBLE (-2850 2075);
FORCEPROP 1 LAST HDL_TAP TRUE
J 2
(-3175 2000);
DISPLAY 1.595745 (-3175 2000);
PAINT GREEN (-3175 2000);
DISPLAY INVISIBLE (-3175 2000);
FORCEPROP 1 LAST PATH I111
J 2
(-2848 2125);
DISPLAY 0.872340 (-2848 2125);
PAINT GREEN (-2848 2125);
DISPLAY INVISIBLE (-2848 2125);
FORCEADD TAP..6
R 2
(-2850 2175);
FORCEPROP 3 LASTPIN (-2900 2175) SIG_NAME M_K_MA<5>
J 0
(-2890 2185);
DISPLAY 0.659574 (-2890 2185);
PAINT MONO (-2890 2185);
DISPLAY INVISIBLE (-2890 2185);
FORCEPROP 1 LASTPIN (-2900 2175) BN 5
J 2
(-2848 2183);
DISPLAY 0.617021 (-2848 2183);
PAINT GREEN (-2848 2183);
FORCEPROP 2 LAST CDS_LIB mstr_standard
J 0
(-2850 2175);
PAINT MONO (-2850 2175);
DISPLAY INVISIBLE (-2850 2175);
FORCEPROP 1 LAST BODY_TYPE PLUMBING
J 2
(-2850 2125);
DISPLAY 1.595745 (-2850 2125);
PAINT GREEN (-2850 2125);
DISPLAY INVISIBLE (-2850 2125);
FORCEPROP 1 LAST HDL_TAP TRUE
J 2
(-3175 2050);
DISPLAY 1.595745 (-3175 2050);
PAINT GREEN (-3175 2050);
DISPLAY INVISIBLE (-3175 2050);
FORCEPROP 1 LAST PATH I112
J 2
(-2848 2175);
DISPLAY 0.872340 (-2848 2175);
PAINT GREEN (-2848 2175);
DISPLAY INVISIBLE (-2848 2175);
FORCEADD TAP..6
R 2
(-2850 2225);
FORCEPROP 3 LASTPIN (-2900 2225) SIG_NAME M_K_MA<6>
J 0
(-2890 2235);
DISPLAY 0.659574 (-2890 2235);
PAINT MONO (-2890 2235);
DISPLAY INVISIBLE (-2890 2235);
FORCEPROP 1 LASTPIN (-2900 2225) BN 6
J 2
(-2848 2233);
DISPLAY 0.617021 (-2848 2233);
PAINT GREEN (-2848 2233);
FORCEPROP 2 LAST CDS_LIB mstr_standard
J 0
(-2850 2225);
PAINT MONO (-2850 2225);
DISPLAY INVISIBLE (-2850 2225);
FORCEPROP 1 LAST BODY_TYPE PLUMBING
J 2
(-2850 2175);
DISPLAY 1.595745 (-2850 2175);
PAINT GREEN (-2850 2175);
DISPLAY INVISIBLE (-2850 2175);
FORCEPROP 1 LAST HDL_TAP TRUE
J 2
(-3175 2100);
DISPLAY 1.595745 (-3175 2100);
PAINT GREEN (-3175 2100);
DISPLAY INVISIBLE (-3175 2100);
FORCEPROP 1 LAST PATH I113
J 2
(-2848 2225);
DISPLAY 0.872340 (-2848 2225);
PAINT GREEN (-2848 2225);
DISPLAY INVISIBLE (-2848 2225);
FORCEADD TAP..6
R 2
(-2850 2325);
FORCEPROP 3 LASTPIN (-2900 2325) SIG_NAME M_K_MA<8>
J 0
(-2890 2335);
DISPLAY 0.659574 (-2890 2335);
PAINT MONO (-2890 2335);
DISPLAY INVISIBLE (-2890 2335);
FORCEPROP 1 LASTPIN (-2900 2325) BN 8
J 2
(-2848 2333);
DISPLAY 0.617021 (-2848 2333);
PAINT GREEN (-2848 2333);
FORCEPROP 2 LAST CDS_LIB mstr_standard
J 0
(-2850 2325);
PAINT MONO (-2850 2325);
DISPLAY INVISIBLE (-2850 2325);
FORCEPROP 1 LAST BODY_TYPE PLUMBING
J 2
(-2850 2275);
DISPLAY 1.595745 (-2850 2275);
PAINT GREEN (-2850 2275);
DISPLAY INVISIBLE (-2850 2275);
FORCEPROP 1 LAST HDL_TAP TRUE
J 2
(-3175 2200);
DISPLAY 1.595745 (-3175 2200);
PAINT GREEN (-3175 2200);
DISPLAY INVISIBLE (-3175 2200);
FORCEPROP 1 LAST PATH I114
J 2
(-2848 2325);
DISPLAY 0.872340 (-2848 2325);
PAINT GREEN (-2848 2325);
DISPLAY INVISIBLE (-2848 2325);
FORCEADD TAP..6
R 2
(-2850 2275);
FORCEPROP 3 LASTPIN (-2900 2275) SIG_NAME M_K_MA<7>
J 0
(-2890 2285);
DISPLAY 0.659574 (-2890 2285);
PAINT MONO (-2890 2285);
DISPLAY INVISIBLE (-2890 2285);
FORCEPROP 1 LASTPIN (-2900 2275) BN 7
J 2
(-2848 2283);
DISPLAY 0.617021 (-2848 2283);
PAINT GREEN (-2848 2283);
FORCEPROP 2 LAST CDS_LIB mstr_standard
J 0
(-2850 2275);
PAINT MONO (-2850 2275);
DISPLAY INVISIBLE (-2850 2275);
FORCEPROP 1 LAST BODY_TYPE PLUMBING
J 2
(-2850 2225);
DISPLAY 1.595745 (-2850 2225);
PAINT GREEN (-2850 2225);
DISPLAY INVISIBLE (-2850 2225);
FORCEPROP 1 LAST HDL_TAP TRUE
J 2
(-3175 2150);
DISPLAY 1.595745 (-3175 2150);
PAINT GREEN (-3175 2150);
DISPLAY INVISIBLE (-3175 2150);
FORCEPROP 1 LAST PATH I115
J 2
(-2848 2275);
DISPLAY 0.872340 (-2848 2275);
PAINT GREEN (-2848 2275);
DISPLAY INVISIBLE (-2848 2275);
FORCEADD TAP..6
R 2
(-2850 2475);
FORCEPROP 3 LASTPIN (-2900 2475) SIG_NAME M_K_MA<11>
J 0
(-2890 2485);
DISPLAY 0.659574 (-2890 2485);
PAINT MONO (-2890 2485);
DISPLAY INVISIBLE (-2890 2485);
FORCEPROP 1 LASTPIN (-2900 2475) BN 11
J 2
(-2848 2483);
DISPLAY 0.617021 (-2848 2483);
PAINT GREEN (-2848 2483);
FORCEPROP 2 LAST CDS_LIB mstr_standard
J 0
(-2850 2475);
PAINT MONO (-2850 2475);
DISPLAY INVISIBLE (-2850 2475);
FORCEPROP 1 LAST BODY_TYPE PLUMBING
J 2
(-2850 2425);
DISPLAY 1.595745 (-2850 2425);
PAINT GREEN (-2850 2425);
DISPLAY INVISIBLE (-2850 2425);
FORCEPROP 1 LAST HDL_TAP TRUE
J 2
(-3175 2350);
DISPLAY 1.595745 (-3175 2350);
PAINT GREEN (-3175 2350);
DISPLAY INVISIBLE (-3175 2350);
FORCEPROP 1 LAST PATH I116
J 2
(-2848 2475);
DISPLAY 0.872340 (-2848 2475);
PAINT GREEN (-2848 2475);
DISPLAY INVISIBLE (-2848 2475);
FORCEADD TAP..6
R 2
(-2850 2425);
FORCEPROP 3 LASTPIN (-2900 2425) SIG_NAME M_K_MA<10>
J 0
(-2890 2435);
DISPLAY 0.659574 (-2890 2435);
PAINT MONO (-2890 2435);
DISPLAY INVISIBLE (-2890 2435);
FORCEPROP 1 LASTPIN (-2900 2425) BN 10
J 2
(-2848 2433);
DISPLAY 0.617021 (-2848 2433);
PAINT GREEN (-2848 2433);
FORCEPROP 2 LAST CDS_LIB mstr_standard
J 0
(-2850 2425);
PAINT MONO (-2850 2425);
DISPLAY INVISIBLE (-2850 2425);
FORCEPROP 1 LAST BODY_TYPE PLUMBING
J 2
(-2850 2375);
DISPLAY 1.595745 (-2850 2375);
PAINT GREEN (-2850 2375);
DISPLAY INVISIBLE (-2850 2375);
FORCEPROP 1 LAST HDL_TAP TRUE
J 2
(-3175 2300);
DISPLAY 1.595745 (-3175 2300);
PAINT GREEN (-3175 2300);
DISPLAY INVISIBLE (-3175 2300);
FORCEPROP 1 LAST PATH I117
J 2
(-2848 2425);
DISPLAY 0.872340 (-2848 2425);
PAINT GREEN (-2848 2425);
DISPLAY INVISIBLE (-2848 2425);
FORCEADD TAP..6
R 2
(-2850 2375);
FORCEPROP 3 LASTPIN (-2900 2375) SIG_NAME M_K_MA<9>
J 0
(-2890 2385);
DISPLAY 0.659574 (-2890 2385);
PAINT MONO (-2890 2385);
DISPLAY INVISIBLE (-2890 2385);
FORCEPROP 1 LASTPIN (-2900 2375) BN 9
J 2
(-2848 2383);
DISPLAY 0.617021 (-2848 2383);
PAINT GREEN (-2848 2383);
FORCEPROP 2 LAST CDS_LIB mstr_standard
J 0
(-2850 2375);
PAINT MONO (-2850 2375);
DISPLAY INVISIBLE (-2850 2375);
FORCEPROP 1 LAST BODY_TYPE PLUMBING
J 2
(-2850 2325);
DISPLAY 1.595745 (-2850 2325);
PAINT GREEN (-2850 2325);
DISPLAY INVISIBLE (-2850 2325);
FORCEPROP 1 LAST HDL_TAP TRUE
J 2
(-3175 2250);
DISPLAY 1.595745 (-3175 2250);
PAINT GREEN (-3175 2250);
DISPLAY INVISIBLE (-3175 2250);
FORCEPROP 1 LAST PATH I118
J 2
(-2848 2375);
DISPLAY 0.872340 (-2848 2375);
PAINT GREEN (-2848 2375);
DISPLAY INVISIBLE (-2848 2375);
FORCEADD TAP..6
R 2
(-2850 2525);
FORCEPROP 3 LASTPIN (-2900 2525) SIG_NAME M_K_MA<12>
J 0
(-2890 2535);
DISPLAY 0.659574 (-2890 2535);
PAINT MONO (-2890 2535);
DISPLAY INVISIBLE (-2890 2535);
FORCEPROP 1 LASTPIN (-2900 2525) BN 12
J 2
(-2848 2533);
DISPLAY 0.617021 (-2848 2533);
PAINT GREEN (-2848 2533);
FORCEPROP 2 LAST CDS_LIB mstr_standard
J 0
(-2850 2525);
PAINT MONO (-2850 2525);
DISPLAY INVISIBLE (-2850 2525);
FORCEPROP 1 LAST BODY_TYPE PLUMBING
J 2
(-2850 2475);
DISPLAY 1.595745 (-2850 2475);
PAINT GREEN (-2850 2475);
DISPLAY INVISIBLE (-2850 2475);
FORCEPROP 1 LAST HDL_TAP TRUE
J 2
(-3175 2400);
DISPLAY 1.595745 (-3175 2400);
PAINT GREEN (-3175 2400);
DISPLAY INVISIBLE (-3175 2400);
FORCEPROP 1 LAST PATH I119
J 2
(-2848 2525);
DISPLAY 0.872340 (-2848 2525);
PAINT GREEN (-2848 2525);
DISPLAY INVISIBLE (-2848 2525);
FORCEADD TAP..6
(-5575 975);
FORCEPROP 3 LASTPIN (-5525 975) SIG_NAME M_K_CLK_DP<3>
J 0
(-5515 985);
DISPLAY 0.659574 (-5515 985);
PAINT MONO (-5515 985);
DISPLAY INVISIBLE (-5515 985);
FORCEPROP 1 LASTPIN (-5525 975) BN 3
J 0
(-5577 983);
DISPLAY 0.617021 (-5577 983);
PAINT GREEN (-5577 983);
FORCEPROP 2 LAST CDS_LIB mstr_standard
J 0
(-5575 975);
PAINT MONO (-5575 975);
DISPLAY INVISIBLE (-5575 975);
FORCEPROP 1 LAST BODY_TYPE PLUMBING
J 0
(-5575 925);
DISPLAY 1.595745 (-5575 925);
PAINT GREEN (-5575 925);
DISPLAY INVISIBLE (-5575 925);
FORCEPROP 1 LAST HDL_TAP TRUE
J 0
(-5250 850);
DISPLAY 1.595745 (-5250 850);
PAINT GREEN (-5250 850);
DISPLAY INVISIBLE (-5250 850);
FORCEPROP 1 LAST PATH I12
J 0
(-5577 975);
DISPLAY 0.872340 (-5577 975);
PAINT GREEN (-5577 975);
DISPLAY INVISIBLE (-5577 975);
FORCEADD TAP..6
R 2
(-2850 2575);
FORCEPROP 3 LASTPIN (-2900 2575) SIG_NAME M_K_MA<13>
J 0
(-2890 2585);
DISPLAY 0.659574 (-2890 2585);
PAINT MONO (-2890 2585);
DISPLAY INVISIBLE (-2890 2585);
FORCEPROP 1 LASTPIN (-2900 2575) BN 13
J 2
(-2848 2583);
DISPLAY 0.617021 (-2848 2583);
PAINT GREEN (-2848 2583);
FORCEPROP 2 LAST CDS_LIB mstr_standard
J 0
(-2850 2575);
PAINT MONO (-2850 2575);
DISPLAY INVISIBLE (-2850 2575);
FORCEPROP 1 LAST BODY_TYPE PLUMBING
J 2
(-2850 2525);
DISPLAY 1.595745 (-2850 2525);
PAINT GREEN (-2850 2525);
DISPLAY INVISIBLE (-2850 2525);
FORCEPROP 1 LAST HDL_TAP TRUE
J 2
(-3175 2450);
DISPLAY 1.595745 (-3175 2450);
PAINT GREEN (-3175 2450);
DISPLAY INVISIBLE (-3175 2450);
FORCEPROP 1 LAST PATH I120
J 2
(-2848 2575);
DISPLAY 0.872340 (-2848 2575);
PAINT GREEN (-2848 2575);
DISPLAY INVISIBLE (-2848 2575);
FORCEADD TAP..6
R 2
(-2850 2625);
FORCEPROP 3 LASTPIN (-2900 2625) SIG_NAME M_K_MA<14>
J 0
(-2890 2635);
DISPLAY 0.659574 (-2890 2635);
PAINT MONO (-2890 2635);
DISPLAY INVISIBLE (-2890 2635);
FORCEPROP 1 LASTPIN (-2900 2625) BN 14
J 2
(-2848 2633);
DISPLAY 0.617021 (-2848 2633);
PAINT GREEN (-2848 2633);
FORCEPROP 2 LAST CDS_LIB mstr_standard
J 0
(-2850 2625);
PAINT MONO (-2850 2625);
DISPLAY INVISIBLE (-2850 2625);
FORCEPROP 1 LAST BODY_TYPE PLUMBING
J 2
(-2850 2575);
DISPLAY 1.595745 (-2850 2575);
PAINT GREEN (-2850 2575);
DISPLAY INVISIBLE (-2850 2575);
FORCEPROP 1 LAST HDL_TAP TRUE
J 2
(-3175 2500);
DISPLAY 1.595745 (-3175 2500);
PAINT GREEN (-3175 2500);
DISPLAY INVISIBLE (-3175 2500);
FORCEPROP 1 LAST PATH I121
J 2
(-2848 2625);
DISPLAY 0.872340 (-2848 2625);
PAINT GREEN (-2848 2625);
DISPLAY INVISIBLE (-2848 2625);
FORCEADD TAP..6
R 2
(-2850 2675);
FORCEPROP 3 LASTPIN (-2900 2675) SIG_NAME M_K_MA<15>
J 0
(-2890 2685);
DISPLAY 0.659574 (-2890 2685);
PAINT MONO (-2890 2685);
DISPLAY INVISIBLE (-2890 2685);
FORCEPROP 1 LASTPIN (-2900 2675) BN 15
J 2
(-2848 2683);
DISPLAY 0.617021 (-2848 2683);
PAINT GREEN (-2848 2683);
FORCEPROP 2 LAST CDS_LIB mstr_standard
J 0
(-2850 2675);
PAINT MONO (-2850 2675);
DISPLAY INVISIBLE (-2850 2675);
FORCEPROP 1 LAST BODY_TYPE PLUMBING
J 2
(-2850 2625);
DISPLAY 1.595745 (-2850 2625);
PAINT GREEN (-2850 2625);
DISPLAY INVISIBLE (-2850 2625);
FORCEPROP 1 LAST HDL_TAP TRUE
J 2
(-3175 2550);
DISPLAY 1.595745 (-3175 2550);
PAINT GREEN (-3175 2550);
DISPLAY INVISIBLE (-3175 2550);
FORCEPROP 1 LAST PATH I122
J 2
(-2848 2675);
DISPLAY 0.872340 (-2848 2675);
PAINT GREEN (-2848 2675);
DISPLAY INVISIBLE (-2848 2675);
FORCEADD TAP..6
R 2
(-2850 2725);
FORCEPROP 3 LASTPIN (-2900 2725) SIG_NAME M_K_MA<16>
J 0
(-2890 2735);
DISPLAY 0.659574 (-2890 2735);
PAINT MONO (-2890 2735);
DISPLAY INVISIBLE (-2890 2735);
FORCEPROP 1 LASTPIN (-2900 2725) BN 16
J 2
(-2848 2733);
DISPLAY 0.617021 (-2848 2733);
PAINT GREEN (-2848 2733);
FORCEPROP 2 LAST CDS_LIB mstr_standard
J 0
(-2850 2725);
PAINT MONO (-2850 2725);
DISPLAY INVISIBLE (-2850 2725);
FORCEPROP 1 LAST BODY_TYPE PLUMBING
J 2
(-2850 2675);
DISPLAY 1.595745 (-2850 2675);
PAINT GREEN (-2850 2675);
DISPLAY INVISIBLE (-2850 2675);
FORCEPROP 1 LAST HDL_TAP TRUE
J 2
(-3175 2600);
DISPLAY 1.595745 (-3175 2600);
PAINT GREEN (-3175 2600);
DISPLAY INVISIBLE (-3175 2600);
FORCEPROP 1 LAST PATH I123
J 2
(-2848 2725);
DISPLAY 0.872340 (-2848 2725);
PAINT GREEN (-2848 2725);
DISPLAY INVISIBLE (-2848 2725);
FORCEADD TAP..6
R 2
(-2850 2775);
FORCEPROP 3 LASTPIN (-2900 2775) SIG_NAME M_K_MA<17>
J 0
(-2890 2785);
DISPLAY 0.659574 (-2890 2785);
PAINT MONO (-2890 2785);
DISPLAY INVISIBLE (-2890 2785);
FORCEPROP 1 LASTPIN (-2900 2775) BN 17
J 2
(-2848 2783);
DISPLAY 0.617021 (-2848 2783);
PAINT GREEN (-2848 2783);
FORCEPROP 2 LAST CDS_LIB mstr_standard
J 0
(-2850 2775);
PAINT MONO (-2850 2775);
DISPLAY INVISIBLE (-2850 2775);
FORCEPROP 1 LAST BODY_TYPE PLUMBING
J 2
(-2850 2725);
DISPLAY 1.595745 (-2850 2725);
PAINT GREEN (-2850 2725);
DISPLAY INVISIBLE (-2850 2725);
FORCEPROP 1 LAST HDL_TAP TRUE
J 2
(-3175 2650);
DISPLAY 1.595745 (-3175 2650);
PAINT GREEN (-3175 2650);
DISPLAY INVISIBLE (-3175 2650);
FORCEPROP 1 LAST PATH I124
J 2
(-2848 2775);
DISPLAY 0.872340 (-2848 2775);
PAINT GREEN (-2848 2775);
DISPLAY INVISIBLE (-2848 2775);
FORCEADD TAP..6
R 2
(-2850 2925);
FORCEPROP 3 LASTPIN (-2900 2925) SIG_NAME M_K_DQS_DN<1>
J 0
(-2890 2935);
DISPLAY 0.659574 (-2890 2935);
PAINT MONO (-2890 2935);
DISPLAY INVISIBLE (-2890 2935);
FORCEPROP 1 LASTPIN (-2900 2925) BN 1
J 2
(-2848 2933);
DISPLAY 0.617021 (-2848 2933);
PAINT GREEN (-2848 2933);
FORCEPROP 2 LAST CDS_LIB mstr_standard
J 0
(-2850 2925);
PAINT MONO (-2850 2925);
DISPLAY INVISIBLE (-2850 2925);
FORCEPROP 1 LAST BODY_TYPE PLUMBING
J 2
(-2850 2875);
DISPLAY 1.595745 (-2850 2875);
PAINT GREEN (-2850 2875);
DISPLAY INVISIBLE (-2850 2875);
FORCEPROP 1 LAST HDL_TAP TRUE
J 2
(-3175 2800);
DISPLAY 1.595745 (-3175 2800);
PAINT GREEN (-3175 2800);
DISPLAY INVISIBLE (-3175 2800);
FORCEPROP 1 LAST PATH I125
J 2
(-2848 2925);
DISPLAY 0.872340 (-2848 2925);
PAINT GREEN (-2848 2925);
DISPLAY INVISIBLE (-2848 2925);
FORCEADD TAP..6
R 2
(-2850 2975);
FORCEPROP 3 LASTPIN (-2900 2975) SIG_NAME M_K_DQS_DN<2>
J 0
(-2890 2985);
DISPLAY 0.659574 (-2890 2985);
PAINT MONO (-2890 2985);
DISPLAY INVISIBLE (-2890 2985);
FORCEPROP 1 LASTPIN (-2900 2975) BN 2
J 2
(-2848 2983);
DISPLAY 0.617021 (-2848 2983);
PAINT GREEN (-2848 2983);
FORCEPROP 2 LAST CDS_LIB mstr_standard
J 0
(-2850 2975);
PAINT MONO (-2850 2975);
DISPLAY INVISIBLE (-2850 2975);
FORCEPROP 1 LAST BODY_TYPE PLUMBING
J 2
(-2850 2925);
DISPLAY 1.595745 (-2850 2925);
PAINT GREEN (-2850 2925);
DISPLAY INVISIBLE (-2850 2925);
FORCEPROP 1 LAST HDL_TAP TRUE
J 2
(-3175 2850);
DISPLAY 1.595745 (-3175 2850);
PAINT GREEN (-3175 2850);
DISPLAY INVISIBLE (-3175 2850);
FORCEPROP 1 LAST PATH I126
J 2
(-2848 2975);
DISPLAY 0.872340 (-2848 2975);
PAINT GREEN (-2848 2975);
DISPLAY INVISIBLE (-2848 2975);
FORCEADD TAP..6
R 2
(-2850 2875);
FORCEPROP 3 LASTPIN (-2900 2875) SIG_NAME M_K_DQS_DN<0>
J 0
(-2890 2885);
DISPLAY 0.659574 (-2890 2885);
PAINT MONO (-2890 2885);
DISPLAY INVISIBLE (-2890 2885);
FORCEPROP 1 LASTPIN (-2900 2875) BN 0
J 2
(-2848 2883);
DISPLAY 0.617021 (-2848 2883);
PAINT GREEN (-2848 2883);
FORCEPROP 2 LAST CDS_LIB mstr_standard
J 0
(-2850 2875);
PAINT MONO (-2850 2875);
DISPLAY INVISIBLE (-2850 2875);
FORCEPROP 1 LAST BODY_TYPE PLUMBING
J 2
(-2850 2825);
DISPLAY 1.595745 (-2850 2825);
PAINT GREEN (-2850 2825);
DISPLAY INVISIBLE (-2850 2825);
FORCEPROP 1 LAST HDL_TAP TRUE
J 2
(-3175 2750);
DISPLAY 1.595745 (-3175 2750);
PAINT GREEN (-3175 2750);
DISPLAY INVISIBLE (-3175 2750);
FORCEPROP 1 LAST PATH I127
J 2
(-2848 2875);
DISPLAY 0.872340 (-2848 2875);
PAINT GREEN (-2848 2875);
DISPLAY INVISIBLE (-2848 2875);
FORCEADD TAP..6
R 2
(-2850 3075);
FORCEPROP 3 LASTPIN (-2900 3075) SIG_NAME M_K_DQS_DN<4>
J 0
(-2890 3085);
DISPLAY 0.659574 (-2890 3085);
PAINT MONO (-2890 3085);
DISPLAY INVISIBLE (-2890 3085);
FORCEPROP 1 LASTPIN (-2900 3075) BN 4
J 2
(-2848 3083);
DISPLAY 0.617021 (-2848 3083);
PAINT GREEN (-2848 3083);
FORCEPROP 2 LAST CDS_LIB mstr_standard
J 0
(-2850 3075);
PAINT MONO (-2850 3075);
DISPLAY INVISIBLE (-2850 3075);
FORCEPROP 1 LAST BODY_TYPE PLUMBING
J 2
(-2850 3025);
DISPLAY 1.595745 (-2850 3025);
PAINT GREEN (-2850 3025);
DISPLAY INVISIBLE (-2850 3025);
FORCEPROP 1 LAST HDL_TAP TRUE
J 2
(-3175 2950);
DISPLAY 1.595745 (-3175 2950);
PAINT GREEN (-3175 2950);
DISPLAY INVISIBLE (-3175 2950);
FORCEPROP 1 LAST PATH I128
J 2
(-2848 3075);
DISPLAY 0.872340 (-2848 3075);
PAINT GREEN (-2848 3075);
DISPLAY INVISIBLE (-2848 3075);
FORCEADD TAP..6
R 2
(-2850 3025);
FORCEPROP 3 LASTPIN (-2900 3025) SIG_NAME M_K_DQS_DN<3>
J 0
(-2890 3035);
DISPLAY 0.659574 (-2890 3035);
PAINT MONO (-2890 3035);
DISPLAY INVISIBLE (-2890 3035);
FORCEPROP 1 LASTPIN (-2900 3025) BN 3
J 2
(-2848 3033);
DISPLAY 0.617021 (-2848 3033);
PAINT GREEN (-2848 3033);
FORCEPROP 2 LAST CDS_LIB mstr_standard
J 0
(-2850 3025);
PAINT MONO (-2850 3025);
DISPLAY INVISIBLE (-2850 3025);
FORCEPROP 1 LAST BODY_TYPE PLUMBING
J 2
(-2850 2975);
DISPLAY 1.595745 (-2850 2975);
PAINT GREEN (-2850 2975);
DISPLAY INVISIBLE (-2850 2975);
FORCEPROP 1 LAST HDL_TAP TRUE
J 2
(-3175 2900);
DISPLAY 1.595745 (-3175 2900);
PAINT GREEN (-3175 2900);
DISPLAY INVISIBLE (-3175 2900);
FORCEPROP 1 LAST PATH I129
J 2
(-2848 3025);
DISPLAY 0.872340 (-2848 3025);
PAINT GREEN (-2848 3025);
DISPLAY INVISIBLE (-2848 3025);
FORCEADD TAP..6
(-5575 1075);
FORCEPROP 3 LASTPIN (-5525 1075) SIG_NAME M_K_ECC<0>
J 0
(-5515 1085);
DISPLAY 0.659574 (-5515 1085);
PAINT MONO (-5515 1085);
DISPLAY INVISIBLE (-5515 1085);
FORCEPROP 1 LASTPIN (-5525 1075) BN 0
J 0
(-5577 1083);
DISPLAY 0.617021 (-5577 1083);
PAINT GREEN (-5577 1083);
FORCEPROP 2 LAST CDS_LIB mstr_standard
J 0
(-5575 1075);
PAINT MONO (-5575 1075);
DISPLAY INVISIBLE (-5575 1075);
FORCEPROP 1 LAST BODY_TYPE PLUMBING
J 0
(-5575 1025);
DISPLAY 1.595745 (-5575 1025);
PAINT GREEN (-5575 1025);
DISPLAY INVISIBLE (-5575 1025);
FORCEPROP 1 LAST HDL_TAP TRUE
J 0
(-5250 950);
DISPLAY 1.595745 (-5250 950);
PAINT GREEN (-5250 950);
DISPLAY INVISIBLE (-5250 950);
FORCEPROP 1 LAST PATH I13
J 0
(-5577 1075);
DISPLAY 0.872340 (-5577 1075);
PAINT GREEN (-5577 1075);
DISPLAY INVISIBLE (-5577 1075);
FORCEADD TAP..6
R 2
(-2850 3125);
FORCEPROP 3 LASTPIN (-2900 3125) SIG_NAME M_K_DQS_DN<5>
J 0
(-2890 3135);
DISPLAY 0.659574 (-2890 3135);
PAINT MONO (-2890 3135);
DISPLAY INVISIBLE (-2890 3135);
FORCEPROP 1 LASTPIN (-2900 3125) BN 5
J 2
(-2848 3133);
DISPLAY 0.617021 (-2848 3133);
PAINT GREEN (-2848 3133);
FORCEPROP 2 LAST CDS_LIB mstr_standard
J 0
(-2850 3125);
PAINT MONO (-2850 3125);
DISPLAY INVISIBLE (-2850 3125);
FORCEPROP 1 LAST BODY_TYPE PLUMBING
J 2
(-2850 3075);
DISPLAY 1.595745 (-2850 3075);
PAINT GREEN (-2850 3075);
DISPLAY INVISIBLE (-2850 3075);
FORCEPROP 1 LAST HDL_TAP TRUE
J 2
(-3175 3000);
DISPLAY 1.595745 (-3175 3000);
PAINT GREEN (-3175 3000);
DISPLAY INVISIBLE (-3175 3000);
FORCEPROP 1 LAST PATH I130
J 2
(-2848 3125);
DISPLAY 0.872340 (-2848 3125);
PAINT GREEN (-2848 3125);
DISPLAY INVISIBLE (-2848 3125);
FORCEADD TAP..6
R 2
(-2850 3175);
FORCEPROP 3 LASTPIN (-2900 3175) SIG_NAME M_K_DQS_DN<6>
J 0
(-2890 3185);
DISPLAY 0.659574 (-2890 3185);
PAINT MONO (-2890 3185);
DISPLAY INVISIBLE (-2890 3185);
FORCEPROP 1 LASTPIN (-2900 3175) BN 6
J 2
(-2848 3183);
DISPLAY 0.617021 (-2848 3183);
PAINT GREEN (-2848 3183);
FORCEPROP 2 LAST CDS_LIB mstr_standard
J 0
(-2850 3175);
PAINT MONO (-2850 3175);
DISPLAY INVISIBLE (-2850 3175);
FORCEPROP 1 LAST BODY_TYPE PLUMBING
J 2
(-2850 3125);
DISPLAY 1.595745 (-2850 3125);
PAINT GREEN (-2850 3125);
DISPLAY INVISIBLE (-2850 3125);
FORCEPROP 1 LAST HDL_TAP TRUE
J 2
(-3175 3050);
DISPLAY 1.595745 (-3175 3050);
PAINT GREEN (-3175 3050);
DISPLAY INVISIBLE (-3175 3050);
FORCEPROP 1 LAST PATH I131
J 2
(-2848 3175);
DISPLAY 0.872340 (-2848 3175);
PAINT GREEN (-2848 3175);
DISPLAY INVISIBLE (-2848 3175);
FORCEADD TAP..6
R 2
(-2850 3225);
FORCEPROP 3 LASTPIN (-2900 3225) SIG_NAME M_K_DQS_DN<7>
J 0
(-2890 3235);
DISPLAY 0.659574 (-2890 3235);
PAINT MONO (-2890 3235);
DISPLAY INVISIBLE (-2890 3235);
FORCEPROP 1 LASTPIN (-2900 3225) BN 7
J 2
(-2848 3233);
DISPLAY 0.617021 (-2848 3233);
PAINT GREEN (-2848 3233);
FORCEPROP 2 LAST CDS_LIB mstr_standard
J 0
(-2850 3225);
PAINT MONO (-2850 3225);
DISPLAY INVISIBLE (-2850 3225);
FORCEPROP 1 LAST BODY_TYPE PLUMBING
J 2
(-2850 3175);
DISPLAY 1.595745 (-2850 3175);
PAINT GREEN (-2850 3175);
DISPLAY INVISIBLE (-2850 3175);
FORCEPROP 1 LAST HDL_TAP TRUE
J 2
(-3175 3100);
DISPLAY 1.595745 (-3175 3100);
PAINT GREEN (-3175 3100);
DISPLAY INVISIBLE (-3175 3100);
FORCEPROP 1 LAST PATH I132
J 2
(-2848 3225);
DISPLAY 0.872340 (-2848 3225);
PAINT GREEN (-2848 3225);
DISPLAY INVISIBLE (-2848 3225);
FORCEADD TAP..6
R 2
(-2850 3275);
FORCEPROP 3 LASTPIN (-2900 3275) SIG_NAME M_K_DQS_DN<8>
J 0
(-2890 3285);
DISPLAY 0.659574 (-2890 3285);
PAINT MONO (-2890 3285);
DISPLAY INVISIBLE (-2890 3285);
FORCEPROP 1 LASTPIN (-2900 3275) BN 8
J 2
(-2848 3283);
DISPLAY 0.617021 (-2848 3283);
PAINT GREEN (-2848 3283);
FORCEPROP 2 LAST CDS_LIB mstr_standard
J 0
(-2850 3275);
PAINT MONO (-2850 3275);
DISPLAY INVISIBLE (-2850 3275);
FORCEPROP 1 LAST BODY_TYPE PLUMBING
J 2
(-2850 3225);
DISPLAY 1.595745 (-2850 3225);
PAINT GREEN (-2850 3225);
DISPLAY INVISIBLE (-2850 3225);
FORCEPROP 1 LAST HDL_TAP TRUE
J 2
(-3175 3150);
DISPLAY 1.595745 (-3175 3150);
PAINT GREEN (-3175 3150);
DISPLAY INVISIBLE (-3175 3150);
FORCEPROP 1 LAST PATH I133
J 2
(-2848 3275);
DISPLAY 0.872340 (-2848 3275);
PAINT GREEN (-2848 3275);
DISPLAY INVISIBLE (-2848 3275);
FORCEADD TAP..6
R 2
(-2850 3325);
FORCEPROP 3 LASTPIN (-2900 3325) SIG_NAME M_K_DQS_DN<9>
J 0
(-2890 3335);
DISPLAY 0.659574 (-2890 3335);
PAINT MONO (-2890 3335);
DISPLAY INVISIBLE (-2890 3335);
FORCEPROP 1 LASTPIN (-2900 3325) BN 9
J 2
(-2848 3333);
DISPLAY 0.617021 (-2848 3333);
PAINT GREEN (-2848 3333);
FORCEPROP 2 LAST CDS_LIB mstr_standard
J 0
(-2850 3325);
PAINT MONO (-2850 3325);
DISPLAY INVISIBLE (-2850 3325);
FORCEPROP 1 LAST BODY_TYPE PLUMBING
J 2
(-2850 3275);
DISPLAY 1.595745 (-2850 3275);
PAINT GREEN (-2850 3275);
DISPLAY INVISIBLE (-2850 3275);
FORCEPROP 1 LAST HDL_TAP TRUE
J 2
(-3175 3200);
DISPLAY 1.595745 (-3175 3200);
PAINT GREEN (-3175 3200);
DISPLAY INVISIBLE (-3175 3200);
FORCEPROP 1 LAST PATH I134
J 2
(-2848 3325);
DISPLAY 0.872340 (-2848 3325);
PAINT GREEN (-2848 3325);
DISPLAY INVISIBLE (-2848 3325);
FORCEADD TAP..6
R 2
(-2850 3375);
FORCEPROP 3 LASTPIN (-2900 3375) SIG_NAME M_K_DQS_DN<10>
J 0
(-2890 3385);
DISPLAY 0.659574 (-2890 3385);
PAINT MONO (-2890 3385);
DISPLAY INVISIBLE (-2890 3385);
FORCEPROP 1 LASTPIN (-2900 3375) BN 10
J 2
(-2848 3383);
DISPLAY 0.617021 (-2848 3383);
PAINT GREEN (-2848 3383);
FORCEPROP 2 LAST CDS_LIB mstr_standard
J 0
(-2850 3375);
PAINT MONO (-2850 3375);
DISPLAY INVISIBLE (-2850 3375);
FORCEPROP 1 LAST BODY_TYPE PLUMBING
J 2
(-2850 3325);
DISPLAY 1.595745 (-2850 3325);
PAINT GREEN (-2850 3325);
DISPLAY INVISIBLE (-2850 3325);
FORCEPROP 1 LAST HDL_TAP TRUE
J 2
(-3175 3250);
DISPLAY 1.595745 (-3175 3250);
PAINT GREEN (-3175 3250);
DISPLAY INVISIBLE (-3175 3250);
FORCEPROP 1 LAST PATH I135
J 2
(-2848 3375);
DISPLAY 0.872340 (-2848 3375);
PAINT GREEN (-2848 3375);
DISPLAY INVISIBLE (-2848 3375);
FORCEADD TAP..6
R 2
(-2850 3475);
FORCEPROP 3 LASTPIN (-2900 3475) SIG_NAME M_K_DQS_DN<12>
J 0
(-2890 3485);
DISPLAY 0.659574 (-2890 3485);
PAINT MONO (-2890 3485);
DISPLAY INVISIBLE (-2890 3485);
FORCEPROP 1 LASTPIN (-2900 3475) BN 12
J 2
(-2848 3483);
DISPLAY 0.617021 (-2848 3483);
PAINT GREEN (-2848 3483);
FORCEPROP 2 LAST CDS_LIB mstr_standard
J 0
(-2850 3475);
PAINT MONO (-2850 3475);
DISPLAY INVISIBLE (-2850 3475);
FORCEPROP 1 LAST BODY_TYPE PLUMBING
J 2
(-2850 3425);
DISPLAY 1.595745 (-2850 3425);
PAINT GREEN (-2850 3425);
DISPLAY INVISIBLE (-2850 3425);
FORCEPROP 1 LAST HDL_TAP TRUE
J 2
(-3175 3350);
DISPLAY 1.595745 (-3175 3350);
PAINT GREEN (-3175 3350);
DISPLAY INVISIBLE (-3175 3350);
FORCEPROP 1 LAST PATH I136
J 2
(-2848 3475);
DISPLAY 0.872340 (-2848 3475);
PAINT GREEN (-2848 3475);
DISPLAY INVISIBLE (-2848 3475);
FORCEADD TAP..6
R 2
(-2850 3425);
FORCEPROP 3 LASTPIN (-2900 3425) SIG_NAME M_K_DQS_DN<11>
J 0
(-2890 3435);
DISPLAY 0.659574 (-2890 3435);
PAINT MONO (-2890 3435);
DISPLAY INVISIBLE (-2890 3435);
FORCEPROP 1 LASTPIN (-2900 3425) BN 11
J 2
(-2848 3433);
DISPLAY 0.617021 (-2848 3433);
PAINT GREEN (-2848 3433);
FORCEPROP 2 LAST CDS_LIB mstr_standard
J 0
(-2850 3425);
PAINT MONO (-2850 3425);
DISPLAY INVISIBLE (-2850 3425);
FORCEPROP 1 LAST BODY_TYPE PLUMBING
J 2
(-2850 3375);
DISPLAY 1.595745 (-2850 3375);
PAINT GREEN (-2850 3375);
DISPLAY INVISIBLE (-2850 3375);
FORCEPROP 1 LAST HDL_TAP TRUE
J 2
(-3175 3300);
DISPLAY 1.595745 (-3175 3300);
PAINT GREEN (-3175 3300);
DISPLAY INVISIBLE (-3175 3300);
FORCEPROP 1 LAST PATH I137
J 2
(-2848 3425);
DISPLAY 0.872340 (-2848 3425);
PAINT GREEN (-2848 3425);
DISPLAY INVISIBLE (-2848 3425);
FORCEADD TAP..6
R 2
(-2850 3625);
FORCEPROP 3 LASTPIN (-2900 3625) SIG_NAME M_K_DQS_DN<15>
J 0
(-2890 3635);
DISPLAY 0.659574 (-2890 3635);
PAINT MONO (-2890 3635);
DISPLAY INVISIBLE (-2890 3635);
FORCEPROP 1 LASTPIN (-2900 3625) BN 15
J 2
(-2848 3633);
DISPLAY 0.617021 (-2848 3633);
PAINT GREEN (-2848 3633);
FORCEPROP 2 LAST CDS_LIB mstr_standard
J 0
(-2850 3625);
PAINT MONO (-2850 3625);
DISPLAY INVISIBLE (-2850 3625);
FORCEPROP 1 LAST BODY_TYPE PLUMBING
J 2
(-2850 3575);
DISPLAY 1.595745 (-2850 3575);
PAINT GREEN (-2850 3575);
DISPLAY INVISIBLE (-2850 3575);
FORCEPROP 1 LAST HDL_TAP TRUE
J 2
(-3175 3500);
DISPLAY 1.595745 (-3175 3500);
PAINT GREEN (-3175 3500);
DISPLAY INVISIBLE (-3175 3500);
FORCEPROP 1 LAST PATH I138
J 2
(-2848 3625);
DISPLAY 0.872340 (-2848 3625);
PAINT GREEN (-2848 3625);
DISPLAY INVISIBLE (-2848 3625);
FORCEADD TAP..6
R 2
(-2850 3575);
FORCEPROP 3 LASTPIN (-2900 3575) SIG_NAME M_K_DQS_DN<14>
J 0
(-2890 3585);
DISPLAY 0.659574 (-2890 3585);
PAINT MONO (-2890 3585);
DISPLAY INVISIBLE (-2890 3585);
FORCEPROP 1 LASTPIN (-2900 3575) BN 14
J 2
(-2848 3583);
DISPLAY 0.617021 (-2848 3583);
PAINT GREEN (-2848 3583);
FORCEPROP 2 LAST CDS_LIB mstr_standard
J 0
(-2850 3575);
PAINT MONO (-2850 3575);
DISPLAY INVISIBLE (-2850 3575);
FORCEPROP 1 LAST BODY_TYPE PLUMBING
J 2
(-2850 3525);
DISPLAY 1.595745 (-2850 3525);
PAINT GREEN (-2850 3525);
DISPLAY INVISIBLE (-2850 3525);
FORCEPROP 1 LAST HDL_TAP TRUE
J 2
(-3175 3450);
DISPLAY 1.595745 (-3175 3450);
PAINT GREEN (-3175 3450);
DISPLAY INVISIBLE (-3175 3450);
FORCEPROP 1 LAST PATH I139
J 2
(-2848 3575);
DISPLAY 0.872340 (-2848 3575);
PAINT GREEN (-2848 3575);
DISPLAY INVISIBLE (-2848 3575);
FORCEADD TAP..6
(-5575 1125);
FORCEPROP 3 LASTPIN (-5525 1125) SIG_NAME M_K_ECC<1>
J 0
(-5515 1135);
DISPLAY 0.659574 (-5515 1135);
PAINT MONO (-5515 1135);
DISPLAY INVISIBLE (-5515 1135);
FORCEPROP 1 LASTPIN (-5525 1125) BN 1
J 0
(-5577 1133);
DISPLAY 0.617021 (-5577 1133);
PAINT GREEN (-5577 1133);
FORCEPROP 2 LAST CDS_LIB mstr_standard
J 0
(-5575 1125);
PAINT MONO (-5575 1125);
DISPLAY INVISIBLE (-5575 1125);
FORCEPROP 1 LAST BODY_TYPE PLUMBING
J 0
(-5575 1075);
DISPLAY 1.595745 (-5575 1075);
PAINT GREEN (-5575 1075);
DISPLAY INVISIBLE (-5575 1075);
FORCEPROP 1 LAST HDL_TAP TRUE
J 0
(-5250 1000);
DISPLAY 1.595745 (-5250 1000);
PAINT GREEN (-5250 1000);
DISPLAY INVISIBLE (-5250 1000);
FORCEPROP 1 LAST PATH I14
J 0
(-5577 1125);
DISPLAY 0.872340 (-5577 1125);
PAINT GREEN (-5577 1125);
DISPLAY INVISIBLE (-5577 1125);
FORCEADD TAP..6
R 2
(-2850 3525);
FORCEPROP 3 LASTPIN (-2900 3525) SIG_NAME M_K_DQS_DN<13>
J 0
(-2890 3535);
DISPLAY 0.659574 (-2890 3535);
PAINT MONO (-2890 3535);
DISPLAY INVISIBLE (-2890 3535);
FORCEPROP 1 LASTPIN (-2900 3525) BN 13
J 2
(-2848 3533);
DISPLAY 0.617021 (-2848 3533);
PAINT GREEN (-2848 3533);
FORCEPROP 2 LAST CDS_LIB mstr_standard
J 0
(-2850 3525);
PAINT MONO (-2850 3525);
DISPLAY INVISIBLE (-2850 3525);
FORCEPROP 1 LAST BODY_TYPE PLUMBING
J 2
(-2850 3475);
DISPLAY 1.595745 (-2850 3475);
PAINT GREEN (-2850 3475);
DISPLAY INVISIBLE (-2850 3475);
FORCEPROP 1 LAST HDL_TAP TRUE
J 2
(-3175 3400);
DISPLAY 1.595745 (-3175 3400);
PAINT GREEN (-3175 3400);
DISPLAY INVISIBLE (-3175 3400);
FORCEPROP 1 LAST PATH I140
J 2
(-2848 3525);
DISPLAY 0.872340 (-2848 3525);
PAINT GREEN (-2848 3525);
DISPLAY INVISIBLE (-2848 3525);
FORCEADD TAP..6
R 2
(-2850 3675);
FORCEPROP 3 LASTPIN (-2900 3675) SIG_NAME M_K_DQS_DN<16>
J 0
(-2890 3685);
DISPLAY 0.659574 (-2890 3685);
PAINT MONO (-2890 3685);
DISPLAY INVISIBLE (-2890 3685);
FORCEPROP 1 LASTPIN (-2900 3675) BN 16
J 2
(-2848 3683);
DISPLAY 0.617021 (-2848 3683);
PAINT GREEN (-2848 3683);
FORCEPROP 2 LAST CDS_LIB mstr_standard
J 0
(-2850 3675);
PAINT MONO (-2850 3675);
DISPLAY INVISIBLE (-2850 3675);
FORCEPROP 1 LAST BODY_TYPE PLUMBING
J 2
(-2850 3625);
DISPLAY 1.595745 (-2850 3625);
PAINT GREEN (-2850 3625);
DISPLAY INVISIBLE (-2850 3625);
FORCEPROP 1 LAST HDL_TAP TRUE
J 2
(-3175 3550);
DISPLAY 1.595745 (-3175 3550);
PAINT GREEN (-3175 3550);
DISPLAY INVISIBLE (-3175 3550);
FORCEPROP 1 LAST PATH I141
J 2
(-2848 3675);
DISPLAY 0.872340 (-2848 3675);
PAINT GREEN (-2848 3675);
DISPLAY INVISIBLE (-2848 3675);
FORCEADD TAP..6
R 2
(-2850 3725);
FORCEPROP 3 LASTPIN (-2900 3725) SIG_NAME M_K_DQS_DN<17>
J 0
(-2890 3735);
DISPLAY 0.659574 (-2890 3735);
PAINT MONO (-2890 3735);
DISPLAY INVISIBLE (-2890 3735);
FORCEPROP 1 LASTPIN (-2900 3725) BN 17
J 2
(-2848 3733);
DISPLAY 0.617021 (-2848 3733);
PAINT GREEN (-2848 3733);
FORCEPROP 2 LAST CDS_LIB mstr_standard
J 0
(-2850 3725);
PAINT MONO (-2850 3725);
DISPLAY INVISIBLE (-2850 3725);
FORCEPROP 1 LAST BODY_TYPE PLUMBING
J 2
(-2850 3675);
DISPLAY 1.595745 (-2850 3675);
PAINT GREEN (-2850 3675);
DISPLAY INVISIBLE (-2850 3675);
FORCEPROP 1 LAST HDL_TAP TRUE
J 2
(-3175 3600);
DISPLAY 1.595745 (-3175 3600);
PAINT GREEN (-3175 3600);
DISPLAY INVISIBLE (-3175 3600);
FORCEPROP 1 LAST PATH I142
J 2
(-2848 3725);
DISPLAY 0.872340 (-2848 3725);
PAINT GREEN (-2848 3725);
DISPLAY INVISIBLE (-2848 3725);
FORCEADD TAP..6
R 2
(-2850 3825);
FORCEPROP 3 LASTPIN (-2900 3825) SIG_NAME M_K_DQS_DP<0>
J 0
(-2890 3835);
DISPLAY 0.659574 (-2890 3835);
PAINT MONO (-2890 3835);
DISPLAY INVISIBLE (-2890 3835);
FORCEPROP 1 LASTPIN (-2900 3825) BN 0
J 2
(-2848 3833);
DISPLAY 0.617021 (-2848 3833);
PAINT GREEN (-2848 3833);
FORCEPROP 2 LAST CDS_LIB mstr_standard
J 0
(-2850 3825);
PAINT MONO (-2850 3825);
DISPLAY INVISIBLE (-2850 3825);
FORCEPROP 1 LAST BODY_TYPE PLUMBING
J 2
(-2850 3775);
DISPLAY 1.595745 (-2850 3775);
PAINT GREEN (-2850 3775);
DISPLAY INVISIBLE (-2850 3775);
FORCEPROP 1 LAST HDL_TAP TRUE
J 2
(-3175 3700);
DISPLAY 1.595745 (-3175 3700);
PAINT GREEN (-3175 3700);
DISPLAY INVISIBLE (-3175 3700);
FORCEPROP 1 LAST PATH I143
J 2
(-2848 3825);
DISPLAY 0.872340 (-2848 3825);
PAINT GREEN (-2848 3825);
DISPLAY INVISIBLE (-2848 3825);
FORCEADD TAP..6
R 2
(-2850 3875);
FORCEPROP 3 LASTPIN (-2900 3875) SIG_NAME M_K_DQS_DP<1>
J 0
(-2890 3885);
DISPLAY 0.659574 (-2890 3885);
PAINT MONO (-2890 3885);
DISPLAY INVISIBLE (-2890 3885);
FORCEPROP 1 LASTPIN (-2900 3875) BN 1
J 2
(-2848 3883);
DISPLAY 0.617021 (-2848 3883);
PAINT GREEN (-2848 3883);
FORCEPROP 2 LAST CDS_LIB mstr_standard
J 0
(-2850 3875);
PAINT MONO (-2850 3875);
DISPLAY INVISIBLE (-2850 3875);
FORCEPROP 1 LAST BODY_TYPE PLUMBING
J 2
(-2850 3825);
DISPLAY 1.595745 (-2850 3825);
PAINT GREEN (-2850 3825);
DISPLAY INVISIBLE (-2850 3825);
FORCEPROP 1 LAST HDL_TAP TRUE
J 2
(-3175 3750);
DISPLAY 1.595745 (-3175 3750);
PAINT GREEN (-3175 3750);
DISPLAY INVISIBLE (-3175 3750);
FORCEPROP 1 LAST PATH I144
J 2
(-2848 3875);
DISPLAY 0.872340 (-2848 3875);
PAINT GREEN (-2848 3875);
DISPLAY INVISIBLE (-2848 3875);
FORCEADD TAP..6
R 2
(-2850 3925);
FORCEPROP 3 LASTPIN (-2900 3925) SIG_NAME M_K_DQS_DP<2>
J 0
(-2890 3935);
DISPLAY 0.659574 (-2890 3935);
PAINT MONO (-2890 3935);
DISPLAY INVISIBLE (-2890 3935);
FORCEPROP 1 LASTPIN (-2900 3925) BN 2
J 2
(-2848 3933);
DISPLAY 0.617021 (-2848 3933);
PAINT GREEN (-2848 3933);
FORCEPROP 2 LAST CDS_LIB mstr_standard
J 0
(-2850 3925);
PAINT MONO (-2850 3925);
DISPLAY INVISIBLE (-2850 3925);
FORCEPROP 1 LAST BODY_TYPE PLUMBING
J 2
(-2850 3875);
DISPLAY 1.595745 (-2850 3875);
PAINT GREEN (-2850 3875);
DISPLAY INVISIBLE (-2850 3875);
FORCEPROP 1 LAST HDL_TAP TRUE
J 2
(-3175 3800);
DISPLAY 1.595745 (-3175 3800);
PAINT GREEN (-3175 3800);
DISPLAY INVISIBLE (-3175 3800);
FORCEPROP 1 LAST PATH I145
J 2
(-2848 3925);
DISPLAY 0.872340 (-2848 3925);
PAINT GREEN (-2848 3925);
DISPLAY INVISIBLE (-2848 3925);
FORCEADD TAP..6
R 2
(-2850 3975);
FORCEPROP 3 LASTPIN (-2900 3975) SIG_NAME M_K_DQS_DP<3>
J 0
(-2890 3985);
DISPLAY 0.659574 (-2890 3985);
PAINT MONO (-2890 3985);
DISPLAY INVISIBLE (-2890 3985);
FORCEPROP 1 LASTPIN (-2900 3975) BN 3
J 2
(-2848 3983);
DISPLAY 0.617021 (-2848 3983);
PAINT GREEN (-2848 3983);
FORCEPROP 2 LAST CDS_LIB mstr_standard
J 0
(-2850 3975);
PAINT MONO (-2850 3975);
DISPLAY INVISIBLE (-2850 3975);
FORCEPROP 1 LAST BODY_TYPE PLUMBING
J 2
(-2850 3925);
DISPLAY 1.595745 (-2850 3925);
PAINT GREEN (-2850 3925);
DISPLAY INVISIBLE (-2850 3925);
FORCEPROP 1 LAST HDL_TAP TRUE
J 2
(-3175 3850);
DISPLAY 1.595745 (-3175 3850);
PAINT GREEN (-3175 3850);
DISPLAY INVISIBLE (-3175 3850);
FORCEPROP 1 LAST PATH I146
J 2
(-2848 3975);
DISPLAY 0.872340 (-2848 3975);
PAINT GREEN (-2848 3975);
DISPLAY INVISIBLE (-2848 3975);
FORCEADD OFFPAGE..2
(-2000 525);
FORCEPROP 2 LAST $XR0 83 
J 0
(-1811 525);
DISPLAY 0.638298 (-1811 525);
PAINT MONO (-1811 525);
FORCEPROP 2 LAST $XR1 84 
J 0
(-1721 525);
DISPLAY 0.638298 (-1721 525);
PAINT MONO (-1721 525);
FORCEPROP 2 LAST CDS_LIB mstr_standard
J 0
(-2000 525);
PAINT MONO (-2000 525);
DISPLAY INVISIBLE (-2000 525);
FORCEPROP 1 LAST OFFPAGE TRUE
J 0
(-1675 400);
DISPLAY 1.170213 (-1675 400);
PAINT GREEN (-1675 400);
DISPLAY INVISIBLE (-1675 400);
FORCEPROP 1 LAST COMMENT_BODY TRUE
J 0
(-2045 430);
DISPLAY 1.170213 (-2045 430);
PAINT GREEN (-2045 430);
DISPLAY INVISIBLE (-2045 430);
FORCEPROP 2 LAST PATH I147
J 0
(-1825 600);
DISPLAY 1.021277 (-1825 600);
PAINT ORANGE (-1825 600);
DISPLAY INVISIBLE (-1825 600);
FORCEADD OFFPAGE..4
(-2000 575);
FORCEPROP 2 LAST $XR0 83 
J 0
(-1814 575);
DISPLAY 0.638298 (-1814 575);
PAINT MONO (-1814 575);
FORCEPROP 2 LAST $XR1 84 
J 0
(-1724 575);
DISPLAY 0.638298 (-1724 575);
PAINT MONO (-1724 575);
FORCEPROP 2 LAST CDS_LIB mstr_standard
J 0
(-2000 575);
PAINT MONO (-2000 575);
DISPLAY INVISIBLE (-2000 575);
FORCEPROP 1 LAST OFFPAGE TRUE
J 0
(-1675 450);
DISPLAY 1.170213 (-1675 450);
PAINT GREEN (-1675 450);
DISPLAY INVISIBLE (-1675 450);
FORCEPROP 1 LAST COMMENT_BODY TRUE
J 0
(-2025 475);
DISPLAY 1.170213 (-2025 475);
PAINT GREEN (-2025 475);
DISPLAY INVISIBLE (-2025 475);
FORCEPROP 2 LAST PATH I148
J 0
(-1825 650);
DISPLAY 1.021277 (-1825 650);
PAINT ORANGE (-1825 650);
DISPLAY INVISIBLE (-1825 650);
FORCEADD OFFPAGE..2
(-2000 625);
FORCEPROP 2 LAST $XR0 83 
J 0
(-1811 625);
DISPLAY 0.638298 (-1811 625);
PAINT MONO (-1811 625);
FORCEPROP 2 LAST $XR1 84 
J 0
(-1721 625);
DISPLAY 0.638298 (-1721 625);
PAINT MONO (-1721 625);
FORCEPROP 2 LAST CDS_LIB mstr_standard
J 0
(-2000 625);
PAINT MONO (-2000 625);
DISPLAY INVISIBLE (-2000 625);
FORCEPROP 1 LAST OFFPAGE TRUE
J 0
(-1675 500);
DISPLAY 1.170213 (-1675 500);
PAINT GREEN (-1675 500);
DISPLAY INVISIBLE (-1675 500);
FORCEPROP 1 LAST COMMENT_BODY TRUE
J 0
(-2045 530);
DISPLAY 1.170213 (-2045 530);
PAINT GREEN (-2045 530);
DISPLAY INVISIBLE (-2045 530);
FORCEPROP 2 LAST PATH I149
J 0
(-1825 700);
DISPLAY 1.021277 (-1825 700);
PAINT ORANGE (-1825 700);
DISPLAY INVISIBLE (-1825 700);
FORCEADD TAP..6
(-5575 1175);
FORCEPROP 3 LASTPIN (-5525 1175) SIG_NAME M_K_ECC<2>
J 0
(-5515 1185);
DISPLAY 0.659574 (-5515 1185);
PAINT MONO (-5515 1185);
DISPLAY INVISIBLE (-5515 1185);
FORCEPROP 1 LASTPIN (-5525 1175) BN 2
J 0
(-5577 1183);
DISPLAY 0.617021 (-5577 1183);
PAINT GREEN (-5577 1183);
FORCEPROP 2 LAST CDS_LIB mstr_standard
J 0
(-5575 1175);
PAINT MONO (-5575 1175);
DISPLAY INVISIBLE (-5575 1175);
FORCEPROP 1 LAST BODY_TYPE PLUMBING
J 0
(-5575 1125);
DISPLAY 1.595745 (-5575 1125);
PAINT GREEN (-5575 1125);
DISPLAY INVISIBLE (-5575 1125);
FORCEPROP 1 LAST HDL_TAP TRUE
J 0
(-5250 1050);
DISPLAY 1.595745 (-5250 1050);
PAINT GREEN (-5250 1050);
DISPLAY INVISIBLE (-5250 1050);
FORCEPROP 1 LAST PATH I15
J 0
(-5577 1175);
DISPLAY 0.872340 (-5577 1175);
PAINT GREEN (-5577 1175);
DISPLAY INVISIBLE (-5577 1175);
FORCEADD OFFPAGE..2
(-2000 825);
FORCEPROP 2 LAST $XR0 83 
J 0
(-1811 825);
DISPLAY 0.638298 (-1811 825);
PAINT MONO (-1811 825);
FORCEPROP 2 LAST $XR1 84 
J 0
(-1721 825);
DISPLAY 0.638298 (-1721 825);
PAINT MONO (-1721 825);
FORCEPROP 2 LAST CDS_LIB mstr_standard
J 0
(-2000 825);
PAINT MONO (-2000 825);
DISPLAY INVISIBLE (-2000 825);
FORCEPROP 1 LAST OFFPAGE TRUE
J 0
(-1675 700);
DISPLAY 1.170213 (-1675 700);
PAINT GREEN (-1675 700);
DISPLAY INVISIBLE (-1675 700);
FORCEPROP 1 LAST COMMENT_BODY TRUE
J 0
(-2045 730);
DISPLAY 1.170213 (-2045 730);
PAINT GREEN (-2045 730);
DISPLAY INVISIBLE (-2045 730);
FORCEPROP 2 LAST PATH I150
J 0
(-1825 900);
DISPLAY 1.021277 (-1825 900);
PAINT ORANGE (-1825 900);
DISPLAY INVISIBLE (-1825 900);
FORCEADD OFFPAGE..2
(-2000 925);
FORCEPROP 2 LAST $XR0 83 
J 0
(-1811 925);
DISPLAY 0.638298 (-1811 925);
PAINT MONO (-1811 925);
FORCEPROP 2 LAST $XR1 84 
J 0
(-1721 925);
DISPLAY 0.638298 (-1721 925);
PAINT MONO (-1721 925);
FORCEPROP 2 LAST CDS_LIB mstr_standard
J 0
(-2000 925);
PAINT MONO (-2000 925);
DISPLAY INVISIBLE (-2000 925);
FORCEPROP 1 LAST OFFPAGE TRUE
J 0
(-1675 800);
DISPLAY 1.170213 (-1675 800);
PAINT GREEN (-1675 800);
DISPLAY INVISIBLE (-1675 800);
FORCEPROP 1 LAST COMMENT_BODY TRUE
J 0
(-2045 830);
DISPLAY 1.170213 (-2045 830);
PAINT GREEN (-2045 830);
DISPLAY INVISIBLE (-2045 830);
FORCEPROP 2 LAST PATH I151
J 0
(-1825 1000);
DISPLAY 1.021277 (-1825 1000);
PAINT ORANGE (-1825 1000);
DISPLAY INVISIBLE (-1825 1000);
FORCEADD OFFPAGE..2
(-2000 1375);
FORCEPROP 2 LAST $XR0 83 
J 0
(-1811 1375);
DISPLAY 0.638298 (-1811 1375);
PAINT MONO (-1811 1375);
FORCEPROP 2 LAST $XR1 84 
J 0
(-1721 1375);
DISPLAY 0.638298 (-1721 1375);
PAINT MONO (-1721 1375);
FORCEPROP 2 LAST CDS_LIB mstr_standard
J 0
(-2000 1375);
PAINT MONO (-2000 1375);
DISPLAY INVISIBLE (-2000 1375);
FORCEPROP 1 LAST OFFPAGE TRUE
J 0
(-1675 1250);
DISPLAY 1.170213 (-1675 1250);
PAINT GREEN (-1675 1250);
DISPLAY INVISIBLE (-1675 1250);
FORCEPROP 1 LAST COMMENT_BODY TRUE
J 0
(-2045 1280);
DISPLAY 1.170213 (-2045 1280);
PAINT GREEN (-2045 1280);
DISPLAY INVISIBLE (-2045 1280);
FORCEPROP 2 LAST PATH I152
J 0
(-1825 1450);
DISPLAY 1.021277 (-1825 1450);
PAINT ORANGE (-1825 1450);
DISPLAY INVISIBLE (-1825 1450);
FORCEADD OFFPAGE..2
(-2000 1625);
FORCEPROP 2 LAST $XR0 83 
J 0
(-1811 1625);
DISPLAY 0.638298 (-1811 1625);
PAINT MONO (-1811 1625);
FORCEPROP 2 LAST $XR1 84 
J 0
(-1721 1625);
DISPLAY 0.638298 (-1721 1625);
PAINT MONO (-1721 1625);
FORCEPROP 2 LAST CDS_LIB mstr_standard
J 0
(-2000 1625);
PAINT MONO (-2000 1625);
DISPLAY INVISIBLE (-2000 1625);
FORCEPROP 1 LAST OFFPAGE TRUE
J 0
(-1675 1500);
DISPLAY 1.170213 (-1675 1500);
PAINT GREEN (-1675 1500);
DISPLAY INVISIBLE (-1675 1500);
FORCEPROP 1 LAST COMMENT_BODY TRUE
J 0
(-2045 1530);
DISPLAY 1.170213 (-2045 1530);
PAINT GREEN (-2045 1530);
DISPLAY INVISIBLE (-2045 1530);
FORCEPROP 2 LAST PATH I153
J 0
(-1825 1700);
DISPLAY 1.021277 (-1825 1700);
PAINT ORANGE (-1825 1700);
DISPLAY INVISIBLE (-1825 1700);
FORCEADD OFFPAGE..2
(-2000 1875);
FORCEPROP 2 LAST $XR0 83 
J 0
(-1811 1875);
DISPLAY 0.638298 (-1811 1875);
PAINT MONO (-1811 1875);
FORCEPROP 2 LAST $XR1 84 
J 0
(-1721 1875);
DISPLAY 0.638298 (-1721 1875);
PAINT MONO (-1721 1875);
FORCEPROP 2 LAST CDS_LIB mstr_standard
J 0
(-2000 1875);
PAINT MONO (-2000 1875);
DISPLAY INVISIBLE (-2000 1875);
FORCEPROP 1 LAST OFFPAGE TRUE
J 0
(-1675 1750);
DISPLAY 1.170213 (-1675 1750);
PAINT GREEN (-1675 1750);
DISPLAY INVISIBLE (-1675 1750);
FORCEPROP 1 LAST COMMENT_BODY TRUE
J 0
(-2045 1780);
DISPLAY 1.170213 (-2045 1780);
PAINT GREEN (-2045 1780);
DISPLAY INVISIBLE (-2045 1780);
FORCEPROP 2 LAST PATH I154
J 0
(-1825 1950);
DISPLAY 1.021277 (-1825 1950);
PAINT ORANGE (-1825 1950);
DISPLAY INVISIBLE (-1825 1950);
FORCEADD OFFPAGE..2
(-2000 2825);
FORCEPROP 2 LAST $XR0 83 
J 0
(-1811 2825);
DISPLAY 0.638298 (-1811 2825);
PAINT MONO (-1811 2825);
FORCEPROP 2 LAST $XR1 84 
J 0
(-1721 2825);
DISPLAY 0.638298 (-1721 2825);
PAINT MONO (-1721 2825);
FORCEPROP 2 LAST CDS_LIB mstr_standard
J 0
(-2000 2825);
PAINT MONO (-2000 2825);
DISPLAY INVISIBLE (-2000 2825);
FORCEPROP 1 LAST OFFPAGE TRUE
J 0
(-1675 2700);
DISPLAY 1.170213 (-1675 2700);
PAINT GREEN (-1675 2700);
DISPLAY INVISIBLE (-1675 2700);
FORCEPROP 1 LAST COMMENT_BODY TRUE
J 0
(-2045 2730);
DISPLAY 1.170213 (-2045 2730);
PAINT GREEN (-2045 2730);
DISPLAY INVISIBLE (-2045 2730);
FORCEPROP 2 LAST PATH I155
J 0
(-1825 2900);
DISPLAY 1.021277 (-1825 2900);
PAINT ORANGE (-1825 2900);
DISPLAY INVISIBLE (-1825 2900);
FORCEADD OFFPAGE..3
(-2000 3775);
FORCEPROP 2 LAST $XR0 83 
J 0
(-1786 3775);
DISPLAY 0.638298 (-1786 3775);
PAINT MONO (-1786 3775);
FORCEPROP 2 LAST $XR1 84 
J 0
(-1696 3775);
DISPLAY 0.638298 (-1696 3775);
PAINT MONO (-1696 3775);
FORCEPROP 2 LAST CDS_LIB mstr_standard
J 0
(-2000 3775);
PAINT MONO (-2000 3775);
DISPLAY INVISIBLE (-2000 3775);
FORCEPROP 1 LAST OFFPAGE TRUE
J 0
(-1675 3650);
DISPLAY 1.170213 (-1675 3650);
PAINT GREEN (-1675 3650);
DISPLAY INVISIBLE (-1675 3650);
FORCEPROP 1 LAST COMMENT_BODY TRUE
J 0
(-2050 3675);
DISPLAY 1.170213 (-2050 3675);
PAINT GREEN (-2050 3675);
DISPLAY INVISIBLE (-2050 3675);
FORCEPROP 2 LAST PATH I156
J 0
(-1800 3850);
DISPLAY 1.021277 (-1800 3850);
PAINT ORANGE (-1800 3850);
DISPLAY INVISIBLE (-1800 3850);
FORCEADD TAP..6
R 2
(-2850 4025);
FORCEPROP 3 LASTPIN (-2900 4025) SIG_NAME M_K_DQS_DP<4>
J 0
(-2890 4035);
DISPLAY 0.659574 (-2890 4035);
PAINT MONO (-2890 4035);
DISPLAY INVISIBLE (-2890 4035);
FORCEPROP 1 LASTPIN (-2900 4025) BN 4
J 2
(-2848 4033);
DISPLAY 0.617021 (-2848 4033);
PAINT GREEN (-2848 4033);
FORCEPROP 2 LAST CDS_LIB mstr_standard
J 0
(-2850 4025);
PAINT MONO (-2850 4025);
DISPLAY INVISIBLE (-2850 4025);
FORCEPROP 1 LAST BODY_TYPE PLUMBING
J 2
(-2850 3975);
DISPLAY 1.595745 (-2850 3975);
PAINT GREEN (-2850 3975);
DISPLAY INVISIBLE (-2850 3975);
FORCEPROP 1 LAST HDL_TAP TRUE
J 2
(-3175 3900);
DISPLAY 1.595745 (-3175 3900);
PAINT GREEN (-3175 3900);
DISPLAY INVISIBLE (-3175 3900);
FORCEPROP 1 LAST PATH I157
J 2
(-2848 4025);
DISPLAY 0.872340 (-2848 4025);
PAINT GREEN (-2848 4025);
DISPLAY INVISIBLE (-2848 4025);
FORCEADD TAP..6
R 2
(-2850 4125);
FORCEPROP 3 LASTPIN (-2900 4125) SIG_NAME M_K_DQS_DP<6>
J 0
(-2890 4135);
DISPLAY 0.659574 (-2890 4135);
PAINT MONO (-2890 4135);
DISPLAY INVISIBLE (-2890 4135);
FORCEPROP 1 LASTPIN (-2900 4125) BN 6
J 2
(-2848 4133);
DISPLAY 0.617021 (-2848 4133);
PAINT GREEN (-2848 4133);
FORCEPROP 2 LAST CDS_LIB mstr_standard
J 0
(-2850 4125);
PAINT MONO (-2850 4125);
DISPLAY INVISIBLE (-2850 4125);
FORCEPROP 1 LAST BODY_TYPE PLUMBING
J 2
(-2850 4075);
DISPLAY 1.595745 (-2850 4075);
PAINT GREEN (-2850 4075);
DISPLAY INVISIBLE (-2850 4075);
FORCEPROP 1 LAST HDL_TAP TRUE
J 2
(-3175 4000);
DISPLAY 1.595745 (-3175 4000);
PAINT GREEN (-3175 4000);
DISPLAY INVISIBLE (-3175 4000);
FORCEPROP 1 LAST PATH I158
J 2
(-2848 4125);
DISPLAY 0.872340 (-2848 4125);
PAINT GREEN (-2848 4125);
DISPLAY INVISIBLE (-2848 4125);
FORCEADD TAP..6
R 2
(-2850 4075);
FORCEPROP 3 LASTPIN (-2900 4075) SIG_NAME M_K_DQS_DP<5>
J 0
(-2890 4085);
DISPLAY 0.659574 (-2890 4085);
PAINT MONO (-2890 4085);
DISPLAY INVISIBLE (-2890 4085);
FORCEPROP 1 LASTPIN (-2900 4075) BN 5
J 2
(-2848 4083);
DISPLAY 0.617021 (-2848 4083);
PAINT GREEN (-2848 4083);
FORCEPROP 2 LAST CDS_LIB mstr_standard
J 0
(-2850 4075);
PAINT MONO (-2850 4075);
DISPLAY INVISIBLE (-2850 4075);
FORCEPROP 1 LAST BODY_TYPE PLUMBING
J 2
(-2850 4025);
DISPLAY 1.595745 (-2850 4025);
PAINT GREEN (-2850 4025);
DISPLAY INVISIBLE (-2850 4025);
FORCEPROP 1 LAST HDL_TAP TRUE
J 2
(-3175 3950);
DISPLAY 1.595745 (-3175 3950);
PAINT GREEN (-3175 3950);
DISPLAY INVISIBLE (-3175 3950);
FORCEPROP 1 LAST PATH I159
J 2
(-2848 4075);
DISPLAY 0.872340 (-2848 4075);
PAINT GREEN (-2848 4075);
DISPLAY INVISIBLE (-2848 4075);
FORCEADD TAP..6
(-5575 1275);
FORCEPROP 3 LASTPIN (-5525 1275) SIG_NAME M_K_ECC<4>
J 0
(-5515 1285);
DISPLAY 0.659574 (-5515 1285);
PAINT MONO (-5515 1285);
DISPLAY INVISIBLE (-5515 1285);
FORCEPROP 1 LASTPIN (-5525 1275) BN 4
J 0
(-5577 1283);
DISPLAY 0.617021 (-5577 1283);
PAINT GREEN (-5577 1283);
FORCEPROP 2 LAST CDS_LIB mstr_standard
J 0
(-5575 1275);
PAINT MONO (-5575 1275);
DISPLAY INVISIBLE (-5575 1275);
FORCEPROP 1 LAST BODY_TYPE PLUMBING
J 0
(-5575 1225);
DISPLAY 1.595745 (-5575 1225);
PAINT GREEN (-5575 1225);
DISPLAY INVISIBLE (-5575 1225);
FORCEPROP 1 LAST HDL_TAP TRUE
J 0
(-5250 1150);
DISPLAY 1.595745 (-5250 1150);
PAINT GREEN (-5250 1150);
DISPLAY INVISIBLE (-5250 1150);
FORCEPROP 1 LAST PATH I16
J 0
(-5577 1275);
DISPLAY 0.872340 (-5577 1275);
PAINT GREEN (-5577 1275);
DISPLAY INVISIBLE (-5577 1275);
FORCEADD TAP..6
R 2
(-2850 4175);
FORCEPROP 3 LASTPIN (-2900 4175) SIG_NAME M_K_DQS_DP<7>
J 0
(-2890 4185);
DISPLAY 0.659574 (-2890 4185);
PAINT MONO (-2890 4185);
DISPLAY INVISIBLE (-2890 4185);
FORCEPROP 1 LASTPIN (-2900 4175) BN 7
J 2
(-2848 4183);
DISPLAY 0.617021 (-2848 4183);
PAINT GREEN (-2848 4183);
FORCEPROP 2 LAST CDS_LIB mstr_standard
J 0
(-2850 4175);
PAINT MONO (-2850 4175);
DISPLAY INVISIBLE (-2850 4175);
FORCEPROP 1 LAST BODY_TYPE PLUMBING
J 2
(-2850 4125);
DISPLAY 1.595745 (-2850 4125);
PAINT GREEN (-2850 4125);
DISPLAY INVISIBLE (-2850 4125);
FORCEPROP 1 LAST HDL_TAP TRUE
J 2
(-3175 4050);
DISPLAY 1.595745 (-3175 4050);
PAINT GREEN (-3175 4050);
DISPLAY INVISIBLE (-3175 4050);
FORCEPROP 1 LAST PATH I160
J 2
(-2848 4175);
DISPLAY 0.872340 (-2848 4175);
PAINT GREEN (-2848 4175);
DISPLAY INVISIBLE (-2848 4175);
FORCEADD TAP..6
R 2
(-2850 4225);
FORCEPROP 3 LASTPIN (-2900 4225) SIG_NAME M_K_DQS_DP<8>
J 0
(-2890 4235);
DISPLAY 0.659574 (-2890 4235);
PAINT MONO (-2890 4235);
DISPLAY INVISIBLE (-2890 4235);
FORCEPROP 1 LASTPIN (-2900 4225) BN 8
J 2
(-2848 4233);
DISPLAY 0.617021 (-2848 4233);
PAINT GREEN (-2848 4233);
FORCEPROP 2 LAST CDS_LIB mstr_standard
J 0
(-2850 4225);
PAINT MONO (-2850 4225);
DISPLAY INVISIBLE (-2850 4225);
FORCEPROP 1 LAST BODY_TYPE PLUMBING
J 2
(-2850 4175);
DISPLAY 1.595745 (-2850 4175);
PAINT GREEN (-2850 4175);
DISPLAY INVISIBLE (-2850 4175);
FORCEPROP 1 LAST HDL_TAP TRUE
J 2
(-3175 4100);
DISPLAY 1.595745 (-3175 4100);
PAINT GREEN (-3175 4100);
DISPLAY INVISIBLE (-3175 4100);
FORCEPROP 1 LAST PATH I161
J 2
(-2848 4225);
DISPLAY 0.872340 (-2848 4225);
PAINT GREEN (-2848 4225);
DISPLAY INVISIBLE (-2848 4225);
FORCEADD TAP..6
R 2
(-2850 4275);
FORCEPROP 3 LASTPIN (-2900 4275) SIG_NAME M_K_DQS_DP<9>
J 0
(-2890 4285);
DISPLAY 0.659574 (-2890 4285);
PAINT MONO (-2890 4285);
DISPLAY INVISIBLE (-2890 4285);
FORCEPROP 1 LASTPIN (-2900 4275) BN 9
J 2
(-2848 4283);
DISPLAY 0.617021 (-2848 4283);
PAINT GREEN (-2848 4283);
FORCEPROP 2 LAST CDS_LIB mstr_standard
J 0
(-2850 4275);
PAINT MONO (-2850 4275);
DISPLAY INVISIBLE (-2850 4275);
FORCEPROP 1 LAST BODY_TYPE PLUMBING
J 2
(-2850 4225);
DISPLAY 1.595745 (-2850 4225);
PAINT GREEN (-2850 4225);
DISPLAY INVISIBLE (-2850 4225);
FORCEPROP 1 LAST HDL_TAP TRUE
J 2
(-3175 4150);
DISPLAY 1.595745 (-3175 4150);
PAINT GREEN (-3175 4150);
DISPLAY INVISIBLE (-3175 4150);
FORCEPROP 1 LAST PATH I162
J 2
(-2848 4275);
DISPLAY 0.872340 (-2848 4275);
PAINT GREEN (-2848 4275);
DISPLAY INVISIBLE (-2848 4275);
FORCEADD TAP..6
R 2
(-2850 4325);
FORCEPROP 3 LASTPIN (-2900 4325) SIG_NAME M_K_DQS_DP<10>
J 0
(-2890 4335);
DISPLAY 0.659574 (-2890 4335);
PAINT MONO (-2890 4335);
DISPLAY INVISIBLE (-2890 4335);
FORCEPROP 1 LASTPIN (-2900 4325) BN 10
J 2
(-2848 4333);
DISPLAY 0.617021 (-2848 4333);
PAINT GREEN (-2848 4333);
FORCEPROP 2 LAST CDS_LIB mstr_standard
J 0
(-2850 4325);
PAINT MONO (-2850 4325);
DISPLAY INVISIBLE (-2850 4325);
FORCEPROP 1 LAST BODY_TYPE PLUMBING
J 2
(-2850 4275);
DISPLAY 1.595745 (-2850 4275);
PAINT GREEN (-2850 4275);
DISPLAY INVISIBLE (-2850 4275);
FORCEPROP 1 LAST HDL_TAP TRUE
J 2
(-3175 4200);
DISPLAY 1.595745 (-3175 4200);
PAINT GREEN (-3175 4200);
DISPLAY INVISIBLE (-3175 4200);
FORCEPROP 1 LAST PATH I163
J 2
(-2848 4325);
DISPLAY 0.872340 (-2848 4325);
PAINT GREEN (-2848 4325);
DISPLAY INVISIBLE (-2848 4325);
FORCEADD TAP..6
R 2
(-2850 4375);
FORCEPROP 3 LASTPIN (-2900 4375) SIG_NAME M_K_DQS_DP<11>
J 0
(-2890 4385);
DISPLAY 0.659574 (-2890 4385);
PAINT MONO (-2890 4385);
DISPLAY INVISIBLE (-2890 4385);
FORCEPROP 1 LASTPIN (-2900 4375) BN 11
J 2
(-2848 4383);
DISPLAY 0.617021 (-2848 4383);
PAINT GREEN (-2848 4383);
FORCEPROP 2 LAST CDS_LIB mstr_standard
J 0
(-2850 4375);
PAINT MONO (-2850 4375);
DISPLAY INVISIBLE (-2850 4375);
FORCEPROP 1 LAST BODY_TYPE PLUMBING
J 2
(-2850 4325);
DISPLAY 1.595745 (-2850 4325);
PAINT GREEN (-2850 4325);
DISPLAY INVISIBLE (-2850 4325);
FORCEPROP 1 LAST HDL_TAP TRUE
J 2
(-3175 4250);
DISPLAY 1.595745 (-3175 4250);
PAINT GREEN (-3175 4250);
DISPLAY INVISIBLE (-3175 4250);
FORCEPROP 1 LAST PATH I164
J 2
(-2848 4375);
DISPLAY 0.872340 (-2848 4375);
PAINT GREEN (-2848 4375);
DISPLAY INVISIBLE (-2848 4375);
FORCEADD TAP..6
R 2
(-2850 4525);
FORCEPROP 3 LASTPIN (-2900 4525) SIG_NAME M_K_DQS_DP<14>
J 0
(-2890 4535);
DISPLAY 0.659574 (-2890 4535);
PAINT MONO (-2890 4535);
DISPLAY INVISIBLE (-2890 4535);
FORCEPROP 1 LASTPIN (-2900 4525) BN 14
J 2
(-2848 4533);
DISPLAY 0.617021 (-2848 4533);
PAINT GREEN (-2848 4533);
FORCEPROP 2 LAST CDS_LIB mstr_standard
J 0
(-2850 4525);
PAINT MONO (-2850 4525);
DISPLAY INVISIBLE (-2850 4525);
FORCEPROP 1 LAST BODY_TYPE PLUMBING
J 2
(-2850 4475);
DISPLAY 1.595745 (-2850 4475);
PAINT GREEN (-2850 4475);
DISPLAY INVISIBLE (-2850 4475);
FORCEPROP 1 LAST HDL_TAP TRUE
J 2
(-3175 4400);
DISPLAY 1.595745 (-3175 4400);
PAINT GREEN (-3175 4400);
DISPLAY INVISIBLE (-3175 4400);
FORCEPROP 1 LAST PATH I165
J 2
(-2848 4525);
DISPLAY 0.872340 (-2848 4525);
PAINT GREEN (-2848 4525);
DISPLAY INVISIBLE (-2848 4525);
FORCEADD TAP..6
R 2
(-2850 4475);
FORCEPROP 3 LASTPIN (-2900 4475) SIG_NAME M_K_DQS_DP<13>
J 0
(-2890 4485);
DISPLAY 0.659574 (-2890 4485);
PAINT MONO (-2890 4485);
DISPLAY INVISIBLE (-2890 4485);
FORCEPROP 1 LASTPIN (-2900 4475) BN 13
J 2
(-2848 4483);
DISPLAY 0.617021 (-2848 4483);
PAINT GREEN (-2848 4483);
FORCEPROP 2 LAST CDS_LIB mstr_standard
J 0
(-2850 4475);
PAINT MONO (-2850 4475);
DISPLAY INVISIBLE (-2850 4475);
FORCEPROP 1 LAST BODY_TYPE PLUMBING
J 2
(-2850 4425);
DISPLAY 1.595745 (-2850 4425);
PAINT GREEN (-2850 4425);
DISPLAY INVISIBLE (-2850 4425);
FORCEPROP 1 LAST HDL_TAP TRUE
J 2
(-3175 4350);
DISPLAY 1.595745 (-3175 4350);
PAINT GREEN (-3175 4350);
DISPLAY INVISIBLE (-3175 4350);
FORCEPROP 1 LAST PATH I166
J 2
(-2848 4475);
DISPLAY 0.872340 (-2848 4475);
PAINT GREEN (-2848 4475);
DISPLAY INVISIBLE (-2848 4475);
FORCEADD TAP..6
R 2
(-2850 4425);
FORCEPROP 3 LASTPIN (-2900 4425) SIG_NAME M_K_DQS_DP<12>
J 0
(-2890 4435);
DISPLAY 0.659574 (-2890 4435);
PAINT MONO (-2890 4435);
DISPLAY INVISIBLE (-2890 4435);
FORCEPROP 1 LASTPIN (-2900 4425) BN 12
J 2
(-2848 4433);
DISPLAY 0.617021 (-2848 4433);
PAINT GREEN (-2848 4433);
FORCEPROP 2 LAST CDS_LIB mstr_standard
J 0
(-2850 4425);
PAINT MONO (-2850 4425);
DISPLAY INVISIBLE (-2850 4425);
FORCEPROP 1 LAST BODY_TYPE PLUMBING
J 2
(-2850 4375);
DISPLAY 1.595745 (-2850 4375);
PAINT GREEN (-2850 4375);
DISPLAY INVISIBLE (-2850 4375);
FORCEPROP 1 LAST HDL_TAP TRUE
J 2
(-3175 4300);
DISPLAY 1.595745 (-3175 4300);
PAINT GREEN (-3175 4300);
DISPLAY INVISIBLE (-3175 4300);
FORCEPROP 1 LAST PATH I167
J 2
(-2848 4425);
DISPLAY 0.872340 (-2848 4425);
PAINT GREEN (-2848 4425);
DISPLAY INVISIBLE (-2848 4425);
FORCEADD TAP..6
R 2
(-2850 4575);
FORCEPROP 3 LASTPIN (-2900 4575) SIG_NAME M_K_DQS_DP<15>
J 0
(-2890 4585);
DISPLAY 0.659574 (-2890 4585);
PAINT MONO (-2890 4585);
DISPLAY INVISIBLE (-2890 4585);
FORCEPROP 1 LASTPIN (-2900 4575) BN 15
J 2
(-2848 4583);
DISPLAY 0.617021 (-2848 4583);
PAINT GREEN (-2848 4583);
FORCEPROP 2 LAST CDS_LIB mstr_standard
J 0
(-2850 4575);
PAINT MONO (-2850 4575);
DISPLAY INVISIBLE (-2850 4575);
FORCEPROP 1 LAST BODY_TYPE PLUMBING
J 2
(-2850 4525);
DISPLAY 1.595745 (-2850 4525);
PAINT GREEN (-2850 4525);
DISPLAY INVISIBLE (-2850 4525);
FORCEPROP 1 LAST HDL_TAP TRUE
J 2
(-3175 4450);
DISPLAY 1.595745 (-3175 4450);
PAINT GREEN (-3175 4450);
DISPLAY INVISIBLE (-3175 4450);
FORCEPROP 1 LAST PATH I168
J 2
(-2848 4575);
DISPLAY 0.872340 (-2848 4575);
PAINT GREEN (-2848 4575);
DISPLAY INVISIBLE (-2848 4575);
FORCEADD TAP..6
R 2
(-2850 4625);
FORCEPROP 3 LASTPIN (-2900 4625) SIG_NAME M_K_DQS_DP<16>
J 0
(-2890 4635);
DISPLAY 0.659574 (-2890 4635);
PAINT MONO (-2890 4635);
DISPLAY INVISIBLE (-2890 4635);
FORCEPROP 1 LASTPIN (-2900 4625) BN 16
J 2
(-2848 4633);
DISPLAY 0.617021 (-2848 4633);
PAINT GREEN (-2848 4633);
FORCEPROP 2 LAST CDS_LIB mstr_standard
J 0
(-2850 4625);
PAINT MONO (-2850 4625);
DISPLAY INVISIBLE (-2850 4625);
FORCEPROP 1 LAST BODY_TYPE PLUMBING
J 2
(-2850 4575);
DISPLAY 1.595745 (-2850 4575);
PAINT GREEN (-2850 4575);
DISPLAY INVISIBLE (-2850 4575);
FORCEPROP 1 LAST HDL_TAP TRUE
J 2
(-3175 4500);
DISPLAY 1.595745 (-3175 4500);
PAINT GREEN (-3175 4500);
DISPLAY INVISIBLE (-3175 4500);
FORCEPROP 1 LAST PATH I169
J 2
(-2848 4625);
DISPLAY 0.872340 (-2848 4625);
PAINT GREEN (-2848 4625);
DISPLAY INVISIBLE (-2848 4625);
FORCEADD TAP..6
(-5575 1225);
FORCEPROP 3 LASTPIN (-5525 1225) SIG_NAME M_K_ECC<3>
J 0
(-5515 1235);
DISPLAY 0.659574 (-5515 1235);
PAINT MONO (-5515 1235);
DISPLAY INVISIBLE (-5515 1235);
FORCEPROP 1 LASTPIN (-5525 1225) BN 3
J 0
(-5577 1233);
DISPLAY 0.617021 (-5577 1233);
PAINT GREEN (-5577 1233);
FORCEPROP 2 LAST CDS_LIB mstr_standard
J 0
(-5575 1225);
PAINT MONO (-5575 1225);
DISPLAY INVISIBLE (-5575 1225);
FORCEPROP 1 LAST BODY_TYPE PLUMBING
J 0
(-5575 1175);
DISPLAY 1.595745 (-5575 1175);
PAINT GREEN (-5575 1175);
DISPLAY INVISIBLE (-5575 1175);
FORCEPROP 1 LAST HDL_TAP TRUE
J 0
(-5250 1100);
DISPLAY 1.595745 (-5250 1100);
PAINT GREEN (-5250 1100);
DISPLAY INVISIBLE (-5250 1100);
FORCEPROP 1 LAST PATH I17
J 0
(-5577 1225);
DISPLAY 0.872340 (-5577 1225);
PAINT GREEN (-5577 1225);
DISPLAY INVISIBLE (-5577 1225);
FORCEADD TAP..6
R 2
(-2850 4675);
FORCEPROP 3 LASTPIN (-2900 4675) SIG_NAME M_K_DQS_DP<17>
J 0
(-2890 4685);
DISPLAY 0.659574 (-2890 4685);
PAINT MONO (-2890 4685);
DISPLAY INVISIBLE (-2890 4685);
FORCEPROP 1 LASTPIN (-2900 4675) BN 17
J 2
(-2848 4683);
DISPLAY 0.617021 (-2848 4683);
PAINT GREEN (-2848 4683);
FORCEPROP 2 LAST CDS_LIB mstr_standard
J 2
(-2850 4675);
PAINT MONO (-2850 4675);
DISPLAY INVISIBLE (-2850 4675);
FORCEPROP 1 LAST BODY_TYPE PLUMBING
J 2
(-2850 4625);
DISPLAY 1.595745 (-2850 4625);
PAINT GREEN (-2850 4625);
DISPLAY INVISIBLE (-2850 4625);
FORCEPROP 1 LAST HDL_TAP TRUE
J 2
(-3175 4550);
DISPLAY 1.595745 (-3175 4550);
PAINT GREEN (-3175 4550);
DISPLAY INVISIBLE (-3175 4550);
FORCEPROP 1 LAST PATH I170
J 2
(-2848 4675);
DISPLAY 0.872340 (-2848 4675);
PAINT GREEN (-2848 4675);
DISPLAY INVISIBLE (-2848 4675);
FORCEADD OFFPAGE..3
(-2000 4750);
FORCEPROP 2 LAST $XR0 83 
J 0
(-1786 4750);
DISPLAY 0.638298 (-1786 4750);
PAINT MONO (-1786 4750);
FORCEPROP 2 LAST $XR1 84 
J 0
(-1696 4750);
DISPLAY 0.638298 (-1696 4750);
PAINT MONO (-1696 4750);
FORCEPROP 2 LAST CDS_LIB mstr_standard
J 0
(-2000 4750);
PAINT MONO (-2000 4750);
DISPLAY INVISIBLE (-2000 4750);
FORCEPROP 1 LAST OFFPAGE TRUE
J 0
(-1675 4625);
DISPLAY 1.170213 (-1675 4625);
PAINT GREEN (-1675 4625);
DISPLAY INVISIBLE (-1675 4625);
FORCEPROP 1 LAST COMMENT_BODY TRUE
J 0
(-2050 4650);
DISPLAY 1.170213 (-2050 4650);
PAINT GREEN (-2050 4650);
DISPLAY INVISIBLE (-2050 4650);
FORCEPROP 2 LAST PATH I171
J 0
(-1800 4825);
DISPLAY 1.021277 (-1800 4825);
PAINT ORANGE (-1800 4825);
DISPLAY INVISIBLE (-1800 4825);
FORCEADD SKX_EXT_B..6
(-4175 2575);
FORCEPROP 1 LAST LOCATION U2D1
J 0
(-4975 4925);
DISPLAY 0.617021 (-4975 4925);
PAINT AQUA (-4975 4925);
FORCEPROP 1 LAST PART_NUMBER TBD
J 0
(-4975 325);
DISPLAY 0.617021 (-4975 325);
PAINT BLUE (-4975 325);
FORCEPROP 1 LAST MATERIAL IC
J 0
(-4975 4875);
DISPLAY 0.617021 (-4975 4875);
PAINT SKYBLUE (-4975 4875);
FORCEPROP 2 LASTPIN (-3325 525) $PN ED53
J 0
(-3315 535);
DISPLAY 0.617021 (-3315 535);
PAINT ORANGE (-3315 535);
FORCEPROP 2 LASTPIN (-3325 1575) $PN EA48
J 0
(-3315 1585);
DISPLAY 0.617021 (-3315 1585);
PAINT ORANGE (-3315 1585);
FORCEPROP 2 LASTPIN (-3325 1525) $PN EA50
J 0
(-3315 1535);
DISPLAY 0.617021 (-3315 1535);
PAINT ORANGE (-3315 1535);
FORCEPROP 2 LASTPIN (-3325 1475) $PN EE48
J 0
(-3315 1485);
DISPLAY 0.617021 (-3315 1485);
PAINT ORANGE (-3315 1485);
FORCEPROP 2 LASTPIN (-3325 1425) $PN EE50
J 0
(-3315 1435);
DISPLAY 0.617021 (-3315 1435);
PAINT ORANGE (-3315 1435);
FORCEPROP 2 LASTPIN (-3325 2775) $PN EA46
J 0
(-3315 2785);
DISPLAY 0.617021 (-3315 2785);
PAINT ORANGE (-3315 2785);
FORCEPROP 2 LASTPIN (-3325 2725) $PN EA52
J 0
(-3315 2735);
DISPLAY 0.617021 (-3315 2735);
PAINT ORANGE (-3315 2735);
FORCEPROP 2 LASTPIN (-3325 2675) $PN DV49
J 0
(-3315 2685);
DISPLAY 0.617021 (-3315 2685);
PAINT ORANGE (-3315 2685);
FORCEPROP 2 LASTPIN (-3325 2625) $PN ED51
J 0
(-3315 2635);
DISPLAY 0.617021 (-3315 2635);
PAINT ORANGE (-3315 2635);
FORCEPROP 2 LASTPIN (-3325 2575) $PN DW48
J 0
(-3315 2585);
DISPLAY 0.617021 (-3315 2585);
PAINT ORANGE (-3315 2585);
FORCEPROP 2 LASTPIN (-3325 2525) $PN DT63
J 0
(-3315 2535);
DISPLAY 0.617021 (-3315 2535);
PAINT ORANGE (-3315 2535);
FORCEPROP 2 LASTPIN (-3325 2475) $PN EB61
J 0
(-3315 2485);
DISPLAY 0.617021 (-3315 2485);
PAINT ORANGE (-3315 2485);
FORCEPROP 2 LASTPIN (-3325 2425) $PN DW54
J 0
(-3315 2435);
DISPLAY 0.617021 (-3315 2435);
PAINT ORANGE (-3315 2435);
FORCEPROP 2 LASTPIN (-3325 2375) $PN EF61
J 0
(-3315 2385);
DISPLAY 0.617021 (-3315 2385);
PAINT ORANGE (-3315 2385);
FORCEPROP 2 LASTPIN (-3325 2325) $PN EB59
J 0
(-3315 2335);
DISPLAY 0.617021 (-3315 2335);
PAINT ORANGE (-3315 2335);
FORCEPROP 2 LASTPIN (-3325 2275) $PN EA60
J 0
(-3315 2285);
DISPLAY 0.617021 (-3315 2285);
PAINT ORANGE (-3315 2285);
FORCEPROP 2 LASTPIN (-3325 2225) $PN EE60
J 0
(-3315 2235);
DISPLAY 0.617021 (-3315 2235);
PAINT ORANGE (-3315 2235);
FORCEPROP 2 LASTPIN (-3325 2175) $PN EA58
J 0
(-3315 2185);
DISPLAY 0.617021 (-3315 2185);
PAINT ORANGE (-3315 2185);
FORCEPROP 2 LASTPIN (-3325 2125) $PN ED59
J 0
(-3315 2135);
DISPLAY 0.617021 (-3315 2135);
PAINT ORANGE (-3315 2135);
FORCEPROP 2 LASTPIN (-3325 2075) $PN EB57
J 0
(-3315 2085);
DISPLAY 0.617021 (-3315 2085);
PAINT ORANGE (-3315 2085);
FORCEPROP 2 LASTPIN (-3325 2025) $PN EE58
J 0
(-3315 2035);
DISPLAY 0.617021 (-3315 2035);
PAINT ORANGE (-3315 2035);
FORCEPROP 2 LASTPIN (-3325 1975) $PN ED57
J 0
(-3315 1985);
DISPLAY 0.617021 (-3315 1985);
PAINT ORANGE (-3315 1985);
FORCEPROP 2 LASTPIN (-3325 1925) $PN EB53
J 0
(-3315 1935);
DISPLAY 0.617021 (-3315 1935);
PAINT ORANGE (-3315 1935);
FORCEPROP 2 LASTPIN (-5025 1425) $PN DE66
J 2
(-5035 1435);
DISPLAY 0.617021 (-5035 1435);
PAINT ORANGE (-5035 1435);
FORCEPROP 2 LASTPIN (-5025 1375) $PN DA66
J 2
(-5035 1385);
DISPLAY 0.617021 (-5035 1385);
PAINT ORANGE (-5035 1385);
FORCEPROP 2 LASTPIN (-5025 1325) $PN DD69
J 2
(-5035 1335);
DISPLAY 0.617021 (-5035 1335);
PAINT ORANGE (-5035 1335);
FORCEPROP 2 LASTPIN (-5025 1275) $PN DB69
J 2
(-5035 1285);
DISPLAY 0.617021 (-5035 1285);
PAINT ORANGE (-5035 1285);
FORCEPROP 2 LASTPIN (-5025 1225) $PN DD65
J 2
(-5035 1235);
DISPLAY 0.617021 (-5035 1235);
PAINT ORANGE (-5035 1235);
FORCEPROP 2 LASTPIN (-5025 1175) $PN DB65
J 2
(-5035 1185);
DISPLAY 0.617021 (-5035 1185);
PAINT ORANGE (-5035 1185);
FORCEPROP 2 LASTPIN (-5025 1125) $PN DE68
J 2
(-5035 1135);
DISPLAY 0.617021 (-5035 1135);
PAINT ORANGE (-5035 1135);
FORCEPROP 2 LASTPIN (-5025 1075) $PN DA68
J 2
(-5035 1085);
DISPLAY 0.617021 (-5035 1085);
PAINT ORANGE (-5035 1085);
FORCEPROP 2 LASTPIN (-3325 4675) $PN CY67
J 0
(-3315 4685);
DISPLAY 0.617021 (-3315 4685);
PAINT ORANGE (-3315 4685);
FORCEPROP 2 LASTPIN (-3325 4625) $PN DP23
J 0
(-3315 4635);
DISPLAY 0.617021 (-3315 4635);
PAINT ORANGE (-3315 4635);
FORCEPROP 2 LASTPIN (-3325 4575) $PN DP29
J 0
(-3315 4585);
DISPLAY 0.617021 (-3315 4585);
PAINT ORANGE (-3315 4585);
FORCEPROP 2 LASTPIN (-3325 4525) $PN DM35
J 0
(-3315 4535);
DISPLAY 0.617021 (-3315 4535);
PAINT ORANGE (-3315 4535);
FORCEPROP 2 LASTPIN (-3325 4475) $PN DW38
J 0
(-3315 4485);
DISPLAY 0.617021 (-3315 4485);
PAINT ORANGE (-3315 4485);
FORCEPROP 2 LASTPIN (-3325 4425) $PN DM75
J 0
(-3315 4435);
DISPLAY 0.617021 (-3315 4435);
PAINT ORANGE (-3315 4435);
FORCEPROP 2 LASTPIN (-3325 4375) $PN DP79
J 0
(-3315 4385);
DISPLAY 0.617021 (-3315 4385);
PAINT ORANGE (-3315 4385);
FORCEPROP 2 LASTPIN (-3325 4325) $PN DL84
J 0
(-3315 4335);
DISPLAY 0.617021 (-3315 4335);
PAINT ORANGE (-3315 4335);
FORCEPROP 2 LASTPIN (-3325 4275) $PN CP85
J 0
(-3315 4285);
DISPLAY 0.617021 (-3315 4285);
PAINT ORANGE (-3315 4285);
FORCEPROP 2 LASTPIN (-3325 4225) $PN DD67
J 0
(-3315 4235);
DISPLAY 0.617021 (-3315 4235);
PAINT ORANGE (-3315 4235);
FORCEPROP 2 LASTPIN (-3325 4175) $PN DT23
J 0
(-3315 4185);
DISPLAY 0.617021 (-3315 4185);
PAINT ORANGE (-3315 4185);
FORCEPROP 2 LASTPIN (-3325 4125) $PN DT29
J 0
(-3315 4135);
DISPLAY 0.617021 (-3315 4135);
PAINT ORANGE (-3315 4135);
FORCEPROP 2 LASTPIN (-3325 4075) $PN DT35
J 0
(-3315 4085);
DISPLAY 0.617021 (-3315 4085);
PAINT ORANGE (-3315 4085);
FORCEPROP 2 LASTPIN (-3325 4025) $PN EC38
J 0
(-3315 4035);
DISPLAY 0.617021 (-3315 4035);
PAINT ORANGE (-3315 4035);
FORCEPROP 2 LASTPIN (-3325 3975) $PN DT75
J 0
(-3315 3985);
DISPLAY 0.617021 (-3315 3985);
PAINT ORANGE (-3315 3985);
FORCEPROP 2 LASTPIN (-3325 3925) $PN DM81
J 0
(-3315 3935);
DISPLAY 0.617021 (-3315 3935);
PAINT ORANGE (-3315 3935);
FORCEPROP 2 LASTPIN (-3325 3875) $PN DP85
J 0
(-3315 3885);
DISPLAY 0.617021 (-3315 3885);
PAINT ORANGE (-3315 3885);
FORCEPROP 2 LASTPIN (-3325 3825) $PN CV85
J 0
(-3315 3835);
DISPLAY 0.617021 (-3315 3835);
PAINT ORANGE (-3315 3835);
FORCEPROP 2 LASTPIN (-3325 3725) $PN DB67
J 0
(-3315 3735);
DISPLAY 0.617021 (-3315 3735);
PAINT ORANGE (-3315 3735);
FORCEPROP 2 LASTPIN (-3325 3675) $PN DM23
J 0
(-3315 3685);
DISPLAY 0.617021 (-3315 3685);
PAINT ORANGE (-3315 3685);
FORCEPROP 2 LASTPIN (-3325 3625) $PN DM29
J 0
(-3315 3635);
DISPLAY 0.617021 (-3315 3635);
PAINT ORANGE (-3315 3635);
FORCEPROP 2 LASTPIN (-3325 3575) $PN DP35
J 0
(-3315 3585);
DISPLAY 0.617021 (-3315 3585);
PAINT ORANGE (-3315 3585);
FORCEPROP 2 LASTPIN (-3325 3525) $PN EA38
J 0
(-3315 3535);
DISPLAY 0.617021 (-3315 3535);
PAINT ORANGE (-3315 3535);
FORCEPROP 2 LASTPIN (-3325 3475) $PN DP75
J 0
(-3315 3485);
DISPLAY 0.617021 (-3315 3485);
PAINT ORANGE (-3315 3485);
FORCEPROP 2 LASTPIN (-3325 3425) $PN DN80
J 0
(-3315 3435);
DISPLAY 0.617021 (-3315 3435);
PAINT ORANGE (-3315 3435);
FORCEPROP 2 LASTPIN (-3325 3375) $PN DM85
J 0
(-3315 3385);
DISPLAY 0.617021 (-3315 3385);
PAINT ORANGE (-3315 3385);
FORCEPROP 2 LASTPIN (-3325 3325) $PN CR84
J 0
(-3315 3335);
DISPLAY 0.617021 (-3315 3335);
PAINT ORANGE (-3315 3335);
FORCEPROP 2 LASTPIN (-3325 3275) $PN DF67
J 0
(-3315 3285);
DISPLAY 0.617021 (-3315 3285);
PAINT ORANGE (-3315 3285);
FORCEPROP 2 LASTPIN (-3325 3225) $PN DV23
J 0
(-3315 3235);
DISPLAY 0.617021 (-3315 3235);
PAINT ORANGE (-3315 3235);
FORCEPROP 2 LASTPIN (-3325 3175) $PN DV29
J 0
(-3315 3185);
DISPLAY 0.617021 (-3315 3185);
PAINT ORANGE (-3315 3185);
FORCEPROP 2 LASTPIN (-3325 3125) $PN DV35
J 0
(-3315 3135);
DISPLAY 0.617021 (-3315 3135);
PAINT ORANGE (-3315 3135);
FORCEPROP 2 LASTPIN (-3325 3075) $PN EE38
J 0
(-3315 3085);
DISPLAY 0.617021 (-3315 3085);
PAINT ORANGE (-3315 3085);
FORCEPROP 2 LASTPIN (-3325 3025) $PN DV75
J 0
(-3315 3035);
DISPLAY 0.617021 (-3315 3035);
PAINT ORANGE (-3315 3035);
FORCEPROP 2 LASTPIN (-3325 2975) $PN DL82
J 0
(-3315 2985);
DISPLAY 0.617021 (-3315 2985);
PAINT ORANGE (-3315 2985);
FORCEPROP 2 LASTPIN (-3325 2925) $PN DN84
J 0
(-3315 2935);
DISPLAY 0.617021 (-3315 2935);
PAINT ORANGE (-3315 2935);
FORCEPROP 2 LASTPIN (-3325 2875) $PN CU84
J 0
(-3315 2885);
DISPLAY 0.617021 (-3315 2885);
PAINT ORANGE (-3315 2885);
FORCEPROP 2 LASTPIN (-5025 4675) $PN DW22
J 2
(-5035 4685);
DISPLAY 0.617021 (-5035 4685);
PAINT ORANGE (-5035 4685);
FORCEPROP 2 LASTPIN (-5025 4625) $PN EC22
J 2
(-5035 4635);
DISPLAY 0.617021 (-5035 4635);
PAINT ORANGE (-5035 4635);
FORCEPROP 2 LASTPIN (-5025 4575) $PN DT25
J 2
(-5035 4585);
DISPLAY 0.617021 (-5035 4585);
PAINT ORANGE (-5035 4585);
FORCEPROP 2 LASTPIN (-5025 4525) $PN DP25
J 2
(-5035 4535);
DISPLAY 0.617021 (-5035 4535);
PAINT ORANGE (-5035 4535);
FORCEPROP 2 LASTPIN (-5025 4475) $PN EB21
J 2
(-5035 4485);
DISPLAY 0.617021 (-5035 4485);
PAINT ORANGE (-5035 4485);
FORCEPROP 2 LASTPIN (-5025 4425) $PN DY21
J 2
(-5035 4435);
DISPLAY 0.617021 (-5035 4435);
PAINT ORANGE (-5035 4435);
FORCEPROP 2 LASTPIN (-5025 4375) $PN DU24
J 2
(-5035 4385);
DISPLAY 0.617021 (-5035 4385);
PAINT ORANGE (-5035 4385);
FORCEPROP 2 LASTPIN (-5025 4325) $PN DN24
J 2
(-5035 4335);
DISPLAY 0.617021 (-5035 4335);
PAINT ORANGE (-5035 4335);
FORCEPROP 2 LASTPIN (-5025 4275) $PN DU28
J 2
(-5035 4285);
DISPLAY 0.617021 (-5035 4285);
PAINT ORANGE (-5035 4285);
FORCEPROP 2 LASTPIN (-5025 4225) $PN DN28
J 2
(-5035 4235);
DISPLAY 0.617021 (-5035 4235);
PAINT ORANGE (-5035 4235);
FORCEPROP 2 LASTPIN (-5025 4175) $PN DT31
J 2
(-5035 4185);
DISPLAY 0.617021 (-5035 4185);
PAINT ORANGE (-5035 4185);
FORCEPROP 2 LASTPIN (-5025 4125) $PN DP31
J 2
(-5035 4135);
DISPLAY 0.617021 (-5035 4135);
PAINT ORANGE (-5035 4135);
FORCEPROP 2 LASTPIN (-5025 4075) $PN DT27
J 2
(-5035 4085);
DISPLAY 0.617021 (-5035 4085);
PAINT ORANGE (-5035 4085);
FORCEPROP 2 LASTPIN (-5025 4025) $PN DP27
J 2
(-5035 4035);
DISPLAY 0.617021 (-5035 4035);
PAINT ORANGE (-5035 4035);
FORCEPROP 2 LASTPIN (-5025 3975) $PN DU30
J 2
(-5035 3985);
DISPLAY 0.617021 (-5035 3985);
PAINT ORANGE (-5035 3985);
FORCEPROP 2 LASTPIN (-5025 3925) $PN DN30
J 2
(-5035 3935);
DISPLAY 0.617021 (-5035 3935);
PAINT ORANGE (-5035 3935);
FORCEPROP 2 LASTPIN (-5025 3875) $PN DU34
J 2
(-5035 3885);
DISPLAY 0.617021 (-5035 3885);
PAINT ORANGE (-5035 3885);
FORCEPROP 2 LASTPIN (-5025 3825) $PN DN34
J 2
(-5035 3835);
DISPLAY 0.617021 (-5035 3835);
PAINT ORANGE (-5035 3835);
FORCEPROP 2 LASTPIN (-5025 3775) $PN DT37
J 2
(-5035 3785);
DISPLAY 0.617021 (-5035 3785);
PAINT ORANGE (-5035 3785);
FORCEPROP 2 LASTPIN (-5025 3725) $PN DP37
J 2
(-5035 3735);
DISPLAY 0.617021 (-5035 3735);
PAINT ORANGE (-5035 3735);
FORCEPROP 2 LASTPIN (-5025 3675) $PN DT33
J 2
(-5035 3685);
DISPLAY 0.617021 (-5035 3685);
PAINT ORANGE (-5035 3685);
FORCEPROP 2 LASTPIN (-5025 3625) $PN DP33
J 2
(-5035 3635);
DISPLAY 0.617021 (-5035 3635);
PAINT ORANGE (-5035 3635);
FORCEPROP 2 LASTPIN (-5025 3575) $PN DU36
J 2
(-5035 3585);
DISPLAY 0.617021 (-5035 3585);
PAINT ORANGE (-5035 3585);
FORCEPROP 2 LASTPIN (-5025 3525) $PN DN36
J 2
(-5035 3535);
DISPLAY 0.617021 (-5035 3535);
PAINT ORANGE (-5035 3535);
FORCEPROP 2 LASTPIN (-5025 3475) $PN ED37
J 2
(-5035 3485);
DISPLAY 0.617021 (-5035 3485);
PAINT ORANGE (-5035 3485);
FORCEPROP 2 LASTPIN (-5025 3425) $PN DY37
J 2
(-5035 3435);
DISPLAY 0.617021 (-5035 3435);
PAINT ORANGE (-5035 3435);
FORCEPROP 2 LASTPIN (-5025 3375) $PN EA40
J 2
(-5035 3385);
DISPLAY 0.617021 (-5035 3385);
PAINT ORANGE (-5035 3385);
FORCEPROP 2 LASTPIN (-5025 3325) $PN DY39
J 2
(-5035 3335);
DISPLAY 0.617021 (-5035 3335);
PAINT ORANGE (-5035 3335);
FORCEPROP 2 LASTPIN (-5025 3275) $PN EC36
J 2
(-5035 3285);
DISPLAY 0.617021 (-5035 3285);
PAINT ORANGE (-5035 3285);
FORCEPROP 2 LASTPIN (-5025 3225) $PN EA36
J 2
(-5035 3235);
DISPLAY 0.617021 (-5035 3235);
PAINT ORANGE (-5035 3235);
FORCEPROP 2 LASTPIN (-5025 3175) $PN ED39
J 2
(-5035 3185);
DISPLAY 0.617021 (-5035 3185);
PAINT ORANGE (-5035 3185);
FORCEPROP 2 LASTPIN (-5025 3125) $PN EC40
J 2
(-5035 3135);
DISPLAY 0.617021 (-5035 3135);
PAINT ORANGE (-5035 3135);
FORCEPROP 2 LASTPIN (-5025 3075) $PN DU74
J 2
(-5035 3085);
DISPLAY 0.617021 (-5035 3085);
PAINT ORANGE (-5035 3085);
FORCEPROP 2 LASTPIN (-5025 3025) $PN DN74
J 2
(-5035 3035);
DISPLAY 0.617021 (-5035 3035);
PAINT ORANGE (-5035 3035);
FORCEPROP 2 LASTPIN (-5025 2975) $PN DT77
J 2
(-5035 2985);
DISPLAY 0.617021 (-5035 2985);
PAINT ORANGE (-5035 2985);
FORCEPROP 2 LASTPIN (-5025 2925) $PN DP77
J 2
(-5035 2935);
DISPLAY 0.617021 (-5035 2935);
PAINT ORANGE (-5035 2935);
FORCEPROP 2 LASTPIN (-5025 2875) $PN DT73
J 2
(-5035 2885);
DISPLAY 0.617021 (-5035 2885);
PAINT ORANGE (-5035 2885);
FORCEPROP 2 LASTPIN (-5025 2825) $PN DP73
J 2
(-5035 2835);
DISPLAY 0.617021 (-5035 2835);
PAINT ORANGE (-5035 2835);
FORCEPROP 2 LASTPIN (-5025 2775) $PN DU76
J 2
(-5035 2785);
DISPLAY 0.617021 (-5035 2785);
PAINT ORANGE (-5035 2785);
FORCEPROP 2 LASTPIN (-5025 2725) $PN DN76
J 2
(-5035 2735);
DISPLAY 0.617021 (-5035 2735);
PAINT ORANGE (-5035 2735);
FORCEPROP 2 LASTPIN (-5025 2675) $PN DN82
J 2
(-5035 2685);
DISPLAY 0.617021 (-5035 2685);
PAINT ORANGE (-5035 2685);
FORCEPROP 2 LASTPIN (-5025 2625) $PN DR80
J 2
(-5035 2635);
DISPLAY 0.617021 (-5035 2635);
PAINT ORANGE (-5035 2635);
FORCEPROP 2 LASTPIN (-5025 2575) $PN DJ80
J 2
(-5035 2585);
DISPLAY 0.617021 (-5035 2585);
PAINT ORANGE (-5035 2585);
FORCEPROP 2 LASTPIN (-5025 2525) $PN DK79
J 2
(-5035 2535);
DISPLAY 0.617021 (-5035 2535);
PAINT ORANGE (-5035 2535);
FORCEPROP 2 LASTPIN (-5025 2475) $PN DR82
J 2
(-5035 2485);
DISPLAY 0.617021 (-5035 2485);
PAINT ORANGE (-5035 2485);
FORCEPROP 2 LASTPIN (-5025 2425) $PN DT81
J 2
(-5035 2435);
DISPLAY 0.617021 (-5035 2435);
PAINT ORANGE (-5035 2435);
FORCEPROP 2 LASTPIN (-5025 2375) $PN DK81
J 2
(-5035 2385);
DISPLAY 0.617021 (-5035 2385);
PAINT ORANGE (-5035 2385);
FORCEPROP 2 LASTPIN (-5025 2325) $PN DM79
J 2
(-5035 2335);
DISPLAY 0.617021 (-5035 2335);
PAINT ORANGE (-5035 2335);
FORCEPROP 2 LASTPIN (-5025 2275) $PN DV85
J 2
(-5035 2285);
DISPLAY 0.617021 (-5035 2285);
PAINT ORANGE (-5035 2285);
FORCEPROP 2 LASTPIN (-5025 2225) $PN DR84
J 2
(-5035 2235);
DISPLAY 0.617021 (-5035 2235);
PAINT ORANGE (-5035 2235);
FORCEPROP 2 LASTPIN (-5025 2175) $PN DE84
J 2
(-5035 2185);
DISPLAY 0.617021 (-5035 2185);
PAINT ORANGE (-5035 2185);
FORCEPROP 2 LASTPIN (-5025 2125) $PN DD85
J 2
(-5035 2135);
DISPLAY 0.617021 (-5035 2135);
PAINT ORANGE (-5035 2135);
FORCEPROP 2 LASTPIN (-5025 2075) $PN DY83
J 2
(-5035 2085);
DISPLAY 0.617021 (-5035 2085);
PAINT ORANGE (-5035 2085);
FORCEPROP 2 LASTPIN (-5025 2025) $PN DV83
J 2
(-5035 2035);
DISPLAY 0.617021 (-5035 2035);
PAINT ORANGE (-5035 2035);
FORCEPROP 2 LASTPIN (-5025 1975) $PN DH85
J 2
(-5035 1985);
DISPLAY 0.617021 (-5035 1985);
PAINT ORANGE (-5035 1985);
FORCEPROP 2 LASTPIN (-5025 1925) $PN DG84
J 2
(-5035 1935);
DISPLAY 0.617021 (-5035 1935);
PAINT ORANGE (-5035 1935);
FORCEPROP 2 LASTPIN (-5025 1875) $PN CW84
J 2
(-5035 1885);
DISPLAY 0.617021 (-5035 1885);
PAINT ORANGE (-5035 1885);
FORCEPROP 2 LASTPIN (-5025 1825) $PN CW86
J 2
(-5035 1835);
DISPLAY 0.617021 (-5035 1835);
PAINT ORANGE (-5035 1835);
FORCEPROP 2 LASTPIN (-5025 1775) $PN CL86
J 2
(-5035 1785);
DISPLAY 0.617021 (-5035 1785);
PAINT ORANGE (-5035 1785);
FORCEPROP 2 LASTPIN (-5025 1725) $PN CL84
J 2
(-5035 1735);
DISPLAY 0.617021 (-5035 1735);
PAINT ORANGE (-5035 1735);
FORCEPROP 2 LASTPIN (-5025 1675) $PN DA84
J 2
(-5035 1685);
DISPLAY 0.617021 (-5035 1685);
PAINT ORANGE (-5035 1685);
FORCEPROP 2 LASTPIN (-5025 1625) $PN DA86
J 2
(-5035 1635);
DISPLAY 0.617021 (-5035 1635);
PAINT ORANGE (-5035 1635);
FORCEPROP 2 LASTPIN (-5025 1575) $PN CN86
J 2
(-5035 1585);
DISPLAY 0.617021 (-5035 1585);
PAINT ORANGE (-5035 1585);
FORCEPROP 2 LASTPIN (-5025 1525) $PN CN84
J 2
(-5035 1535);
DISPLAY 0.617021 (-5035 1535);
PAINT ORANGE (-5035 1535);
FORCEPROP 2 LASTPIN (-3325 1325) $PN EB45
J 0
(-3315 1335);
DISPLAY 0.617021 (-3315 1335);
PAINT ORANGE (-3315 1335);
FORCEPROP 2 LASTPIN (-3325 1275) $PN DV45
J 0
(-3315 1285);
DISPLAY 0.617021 (-3315 1285);
PAINT ORANGE (-3315 1285);
FORCEPROP 2 LASTPIN (-3325 1225) $PN EB49
J 0
(-3315 1235);
DISPLAY 0.617021 (-3315 1235);
PAINT ORANGE (-3315 1235);
FORCEPROP 2 LASTPIN (-3325 1175) $PN EB51
J 0
(-3315 1185);
DISPLAY 0.617021 (-3315 1185);
PAINT ORANGE (-3315 1185);
FORCEPROP 2 LASTPIN (-3325 1125) $PN EB47
J 0
(-3315 1135);
DISPLAY 0.617021 (-3315 1135);
PAINT ORANGE (-3315 1135);
FORCEPROP 2 LASTPIN (-3325 1075) $PN ED47
J 0
(-3315 1085);
DISPLAY 0.617021 (-3315 1085);
PAINT ORANGE (-3315 1085);
FORCEPROP 2 LASTPIN (-3325 1025) $PN ED49
J 0
(-3315 1035);
DISPLAY 0.617021 (-3315 1035);
PAINT ORANGE (-3315 1035);
FORCEPROP 2 LASTPIN (-3325 975) $PN EF51
J 0
(-3315 985);
DISPLAY 0.617021 (-3315 985);
PAINT ORANGE (-3315 985);
FORCEPROP 2 LASTPIN (-5025 975) $PN EE56
J 2
(-5035 985);
DISPLAY 0.617021 (-5035 985);
PAINT ORANGE (-5035 985);
FORCEPROP 2 LASTPIN (-5025 925) $PN EA56
J 2
(-5035 935);
DISPLAY 0.617021 (-5035 935);
PAINT ORANGE (-5035 935);
FORCEPROP 2 LASTPIN (-5025 875) $PN EE54
J 2
(-5035 885);
DISPLAY 0.617021 (-5035 885);
PAINT ORANGE (-5035 885);
FORCEPROP 2 LASTPIN (-5025 825) $PN EB55
J 2
(-5035 835);
DISPLAY 0.617021 (-5035 835);
PAINT ORANGE (-5035 835);
FORCEPROP 2 LASTPIN (-5025 775) $PN EF57
J 2
(-5035 785);
DISPLAY 0.617021 (-5035 785);
PAINT ORANGE (-5035 785);
FORCEPROP 2 LASTPIN (-5025 725) $PN DW56
J 2
(-5035 735);
DISPLAY 0.617021 (-5035 735);
PAINT ORANGE (-5035 735);
FORCEPROP 2 LASTPIN (-5025 675) $PN EF55
J 2
(-5035 685);
DISPLAY 0.617021 (-5035 685);
PAINT ORANGE (-5035 685);
FORCEPROP 2 LASTPIN (-5025 625) $PN ED55
J 2
(-5035 635);
DISPLAY 0.617021 (-5035 635);
PAINT ORANGE (-5035 635);
FORCEPROP 2 LASTPIN (-3325 1825) $PN EB63
J 0
(-3315 1835);
DISPLAY 0.617021 (-3315 1835);
PAINT ORANGE (-3315 1835);
FORCEPROP 2 LASTPIN (-3325 1775) $PN EA62
J 0
(-3315 1785);
DISPLAY 0.617021 (-3315 1785);
PAINT ORANGE (-3315 1785);
FORCEPROP 2 LASTPIN (-3325 1725) $PN EF63
J 0
(-3315 1735);
DISPLAY 0.617021 (-3315 1735);
PAINT ORANGE (-3315 1735);
FORCEPROP 2 LASTPIN (-3325 1675) $PN EE62
J 0
(-3315 1685);
DISPLAY 0.617021 (-3315 1685);
PAINT ORANGE (-3315 1685);
FORCEPROP 2 LASTPIN (-5025 525) $PN DV47
J 2
(-5035 535);
DISPLAY 0.617021 (-5035 535);
PAINT ORANGE (-5035 535);
FORCEPROP 2 LASTPIN (-3325 875) $PN DW62
J 0
(-3315 885);
DISPLAY 0.617021 (-3315 885);
PAINT ORANGE (-3315 885);
FORCEPROP 2 LASTPIN (-3325 825) $PN ED61
J 0
(-3315 835);
DISPLAY 0.617021 (-3315 835);
PAINT ORANGE (-3315 835);
FORCEPROP 2 LASTPIN (-3325 775) $PN EA54
J 0
(-3315 785);
DISPLAY 0.617021 (-3315 785);
PAINT ORANGE (-3315 785);
FORCEPROP 2 LASTPIN (-3325 725) $PN EE52
J 0
(-3315 735);
DISPLAY 0.617021 (-3315 735);
PAINT ORANGE (-3315 735);
FORCEPROP 2 LASTPIN (-3325 575) $PN ED63
J 0
(-3315 585);
DISPLAY 0.617021 (-3315 585);
PAINT ORANGE (-3315 585);
FORCEPROP 2 LASTPIN (-3325 625) $PN DW60
J 0
(-3315 635);
DISPLAY 0.617021 (-3315 635);
PAINT ORANGE (-3315 635);
FORCEPROP 1 LAST PACK_TYPE BGA1
J 0
(-4975 4975);
PAINT SKYBLUE (-4975 4975);
DISPLAY INVISIBLE (-4975 4975);
FORCEPROP 2 LAST SEC_TYPE BGA1
J 0
(-4975 4975);
DISPLAY 1.021277 (-4975 4975);
PAINT ORANGE (-4975 4975);
DISPLAY INVISIBLE (-4975 4975);
FORCEPROP 2 LAST CDS_LIB chpset_lib
J 0
(-4175 2575);
PAINT ORANGE (-4175 2575);
DISPLAY INVISIBLE (-4175 2575);
FORCEPROP 2 LAST SEC 6
J 0
(-4975 4975);
DISPLAY 0.680851 (-4975 4975);
PAINT MONO (-4975 4975);
DISPLAY INVISIBLE (-4975 4975);
FORCEPROP 2 LAST CDS_LOCATION U2D1
J 0
(-4975 4925);
DISPLAY 0.617021 (-4975 4925);
PAINT AQUA (-4975 4925);
DISPLAY INVISIBLE (-4975 4925);
FORCEPROP 1 LAST PATH I172
J 0
(-4175 4875);
PAINT GREEN (-4175 4875);
DISPLAY INVISIBLE (-4175 4875);
FORCEADD TAP..6
(-5575 1325);
FORCEPROP 3 LASTPIN (-5525 1325) SIG_NAME M_K_ECC<5>
J 0
(-5515 1335);
DISPLAY 0.659574 (-5515 1335);
PAINT MONO (-5515 1335);
DISPLAY INVISIBLE (-5515 1335);
FORCEPROP 1 LASTPIN (-5525 1325) BN 5
J 0
(-5577 1333);
DISPLAY 0.617021 (-5577 1333);
PAINT GREEN (-5577 1333);
FORCEPROP 2 LAST CDS_LIB mstr_standard
J 0
(-5575 1325);
PAINT MONO (-5575 1325);
DISPLAY INVISIBLE (-5575 1325);
FORCEPROP 1 LAST BODY_TYPE PLUMBING
J 0
(-5575 1275);
DISPLAY 1.595745 (-5575 1275);
PAINT GREEN (-5575 1275);
DISPLAY INVISIBLE (-5575 1275);
FORCEPROP 1 LAST HDL_TAP TRUE
J 0
(-5250 1200);
DISPLAY 1.595745 (-5250 1200);
PAINT GREEN (-5250 1200);
DISPLAY INVISIBLE (-5250 1200);
FORCEPROP 1 LAST PATH I18
J 0
(-5577 1325);
DISPLAY 0.872340 (-5577 1325);
PAINT GREEN (-5577 1325);
DISPLAY INVISIBLE (-5577 1325);
FORCEADD TAP..6
(-5575 1375);
FORCEPROP 3 LASTPIN (-5525 1375) SIG_NAME M_K_ECC<6>
J 0
(-5515 1385);
DISPLAY 0.659574 (-5515 1385);
PAINT MONO (-5515 1385);
DISPLAY INVISIBLE (-5515 1385);
FORCEPROP 1 LASTPIN (-5525 1375) BN 6
J 0
(-5577 1383);
DISPLAY 0.617021 (-5577 1383);
PAINT GREEN (-5577 1383);
FORCEPROP 2 LAST CDS_LIB mstr_standard
J 0
(-5575 1375);
PAINT MONO (-5575 1375);
DISPLAY INVISIBLE (-5575 1375);
FORCEPROP 1 LAST BODY_TYPE PLUMBING
J 0
(-5575 1325);
DISPLAY 1.595745 (-5575 1325);
PAINT GREEN (-5575 1325);
DISPLAY INVISIBLE (-5575 1325);
FORCEPROP 1 LAST HDL_TAP TRUE
J 0
(-5250 1250);
DISPLAY 1.595745 (-5250 1250);
PAINT GREEN (-5250 1250);
DISPLAY INVISIBLE (-5250 1250);
FORCEPROP 1 LAST PATH I19
J 0
(-5577 1375);
DISPLAY 0.872340 (-5577 1375);
PAINT GREEN (-5577 1375);
DISPLAY INVISIBLE (-5577 1375);
FORCEADD OFFPAGE..5
(-6425 825);
FORCEPROP 2 LAST $XR0 83 
J 0
(-6679 825);
DISPLAY 0.638298 (-6679 825);
PAINT MONO (-6679 825);
FORCEPROP 2 LAST $XR1 84 
J 0
(-6769 825);
DISPLAY 0.638298 (-6769 825);
PAINT MONO (-6769 825);
FORCEPROP 2 LAST CDS_LIB mstr_standard
J 0
(-6425 825);
PAINT MONO (-6425 825);
DISPLAY INVISIBLE (-6425 825);
FORCEPROP 1 LAST OFFPAGE TRUE
J 0
(-6100 700);
DISPLAY 1.170213 (-6100 700);
PAINT GREEN (-6100 700);
DISPLAY INVISIBLE (-6100 700);
FORCEPROP 1 LAST COMMENT_BODY TRUE
J 0
(-6325 750);
DISPLAY 1.170213 (-6325 750);
PAINT GREEN (-6325 750);
DISPLAY INVISIBLE (-6325 750);
FORCEPROP 2 LAST PATH I2
J 0
(-6375 900);
DISPLAY 1.021277 (-6375 900);
PAINT ORANGE (-6375 900);
DISPLAY INVISIBLE (-6375 900);
FORCEADD TAP..6
(-5575 1425);
FORCEPROP 3 LASTPIN (-5525 1425) SIG_NAME M_K_ECC<7>
J 0
(-5515 1435);
DISPLAY 0.659574 (-5515 1435);
PAINT MONO (-5515 1435);
DISPLAY INVISIBLE (-5515 1435);
FORCEPROP 1 LASTPIN (-5525 1425) BN 7
J 0
(-5577 1433);
DISPLAY 0.617021 (-5577 1433);
PAINT GREEN (-5577 1433);
FORCEPROP 2 LAST CDS_LIB mstr_standard
J 0
(-5575 1425);
PAINT MONO (-5575 1425);
DISPLAY INVISIBLE (-5575 1425);
FORCEPROP 1 LAST BODY_TYPE PLUMBING
J 0
(-5575 1375);
DISPLAY 1.595745 (-5575 1375);
PAINT GREEN (-5575 1375);
DISPLAY INVISIBLE (-5575 1375);
FORCEPROP 1 LAST HDL_TAP TRUE
J 0
(-5250 1300);
DISPLAY 1.595745 (-5250 1300);
PAINT GREEN (-5250 1300);
DISPLAY INVISIBLE (-5250 1300);
FORCEPROP 1 LAST PATH I20
J 0
(-5577 1425);
DISPLAY 0.872340 (-5577 1425);
PAINT GREEN (-5577 1425);
DISPLAY INVISIBLE (-5577 1425);
FORCEADD TAP..6
(-5575 1525);
FORCEPROP 3 LASTPIN (-5525 1525) SIG_NAME M_K_DQ<0>
J 0
(-5515 1535);
DISPLAY 0.659574 (-5515 1535);
PAINT MONO (-5515 1535);
DISPLAY INVISIBLE (-5515 1535);
FORCEPROP 1 LASTPIN (-5525 1525) BN 0
J 0
(-5577 1533);
DISPLAY 0.617021 (-5577 1533);
PAINT GREEN (-5577 1533);
FORCEPROP 2 LAST CDS_LIB mstr_standard
J 0
(-5575 1525);
PAINT MONO (-5575 1525);
DISPLAY INVISIBLE (-5575 1525);
FORCEPROP 1 LAST BODY_TYPE PLUMBING
J 0
(-5575 1475);
DISPLAY 1.595745 (-5575 1475);
PAINT GREEN (-5575 1475);
DISPLAY INVISIBLE (-5575 1475);
FORCEPROP 1 LAST HDL_TAP TRUE
J 0
(-5250 1400);
DISPLAY 1.595745 (-5250 1400);
PAINT GREEN (-5250 1400);
DISPLAY INVISIBLE (-5250 1400);
FORCEPROP 1 LAST PATH I21
J 0
(-5577 1525);
DISPLAY 0.872340 (-5577 1525);
PAINT GREEN (-5577 1525);
DISPLAY INVISIBLE (-5577 1525);
FORCEADD TAP..6
(-5575 1575);
FORCEPROP 3 LASTPIN (-5525 1575) SIG_NAME M_K_DQ<1>
J 0
(-5515 1585);
DISPLAY 0.659574 (-5515 1585);
PAINT MONO (-5515 1585);
DISPLAY INVISIBLE (-5515 1585);
FORCEPROP 1 LASTPIN (-5525 1575) BN 1
J 0
(-5577 1583);
DISPLAY 0.617021 (-5577 1583);
PAINT GREEN (-5577 1583);
FORCEPROP 2 LAST CDS_LIB mstr_standard
J 0
(-5575 1575);
PAINT MONO (-5575 1575);
DISPLAY INVISIBLE (-5575 1575);
FORCEPROP 1 LAST BODY_TYPE PLUMBING
J 0
(-5575 1525);
DISPLAY 1.595745 (-5575 1525);
PAINT GREEN (-5575 1525);
DISPLAY INVISIBLE (-5575 1525);
FORCEPROP 1 LAST HDL_TAP TRUE
J 0
(-5250 1450);
DISPLAY 1.595745 (-5250 1450);
PAINT GREEN (-5250 1450);
DISPLAY INVISIBLE (-5250 1450);
FORCEPROP 1 LAST PATH I22
J 0
(-5577 1575);
DISPLAY 0.872340 (-5577 1575);
PAINT GREEN (-5577 1575);
DISPLAY INVISIBLE (-5577 1575);
FORCEADD TAP..6
(-5575 1625);
FORCEPROP 3 LASTPIN (-5525 1625) SIG_NAME M_K_DQ<2>
J 0
(-5515 1635);
DISPLAY 0.659574 (-5515 1635);
PAINT MONO (-5515 1635);
DISPLAY INVISIBLE (-5515 1635);
FORCEPROP 1 LASTPIN (-5525 1625) BN 2
J 0
(-5577 1633);
DISPLAY 0.617021 (-5577 1633);
PAINT GREEN (-5577 1633);
FORCEPROP 2 LAST CDS_LIB mstr_standard
J 0
(-5575 1625);
PAINT MONO (-5575 1625);
DISPLAY INVISIBLE (-5575 1625);
FORCEPROP 1 LAST BODY_TYPE PLUMBING
J 0
(-5575 1575);
DISPLAY 1.595745 (-5575 1575);
PAINT GREEN (-5575 1575);
DISPLAY INVISIBLE (-5575 1575);
FORCEPROP 1 LAST HDL_TAP TRUE
J 0
(-5250 1500);
DISPLAY 1.595745 (-5250 1500);
PAINT GREEN (-5250 1500);
DISPLAY INVISIBLE (-5250 1500);
FORCEPROP 1 LAST PATH I23
J 0
(-5577 1625);
DISPLAY 0.872340 (-5577 1625);
PAINT GREEN (-5577 1625);
DISPLAY INVISIBLE (-5577 1625);
FORCEADD TAP..6
(-5575 1675);
FORCEPROP 3 LASTPIN (-5525 1675) SIG_NAME M_K_DQ<3>
J 0
(-5515 1685);
DISPLAY 0.659574 (-5515 1685);
PAINT MONO (-5515 1685);
DISPLAY INVISIBLE (-5515 1685);
FORCEPROP 1 LASTPIN (-5525 1675) BN 3
J 0
(-5577 1683);
DISPLAY 0.617021 (-5577 1683);
PAINT GREEN (-5577 1683);
FORCEPROP 2 LAST CDS_LIB mstr_standard
J 0
(-5575 1675);
PAINT MONO (-5575 1675);
DISPLAY INVISIBLE (-5575 1675);
FORCEPROP 1 LAST BODY_TYPE PLUMBING
J 0
(-5575 1625);
DISPLAY 1.595745 (-5575 1625);
PAINT GREEN (-5575 1625);
DISPLAY INVISIBLE (-5575 1625);
FORCEPROP 1 LAST HDL_TAP TRUE
J 0
(-5250 1550);
DISPLAY 1.595745 (-5250 1550);
PAINT GREEN (-5250 1550);
DISPLAY INVISIBLE (-5250 1550);
FORCEPROP 1 LAST PATH I24
J 0
(-5577 1675);
DISPLAY 0.872340 (-5577 1675);
PAINT GREEN (-5577 1675);
DISPLAY INVISIBLE (-5577 1675);
FORCEADD TAP..6
(-5575 1725);
FORCEPROP 3 LASTPIN (-5525 1725) SIG_NAME M_K_DQ<4>
J 0
(-5515 1735);
DISPLAY 0.659574 (-5515 1735);
PAINT MONO (-5515 1735);
DISPLAY INVISIBLE (-5515 1735);
FORCEPROP 1 LASTPIN (-5525 1725) BN 4
J 0
(-5577 1733);
DISPLAY 0.617021 (-5577 1733);
PAINT GREEN (-5577 1733);
FORCEPROP 2 LAST CDS_LIB mstr_standard
J 0
(-5575 1725);
PAINT MONO (-5575 1725);
DISPLAY INVISIBLE (-5575 1725);
FORCEPROP 1 LAST BODY_TYPE PLUMBING
J 0
(-5575 1675);
DISPLAY 1.595745 (-5575 1675);
PAINT GREEN (-5575 1675);
DISPLAY INVISIBLE (-5575 1675);
FORCEPROP 1 LAST HDL_TAP TRUE
J 0
(-5250 1600);
DISPLAY 1.595745 (-5250 1600);
PAINT GREEN (-5250 1600);
DISPLAY INVISIBLE (-5250 1600);
FORCEPROP 1 LAST PATH I25
J 0
(-5577 1725);
DISPLAY 0.872340 (-5577 1725);
PAINT GREEN (-5577 1725);
DISPLAY INVISIBLE (-5577 1725);
FORCEADD TAP..6
(-5575 1775);
FORCEPROP 3 LASTPIN (-5525 1775) SIG_NAME M_K_DQ<5>
J 0
(-5515 1785);
DISPLAY 0.659574 (-5515 1785);
PAINT MONO (-5515 1785);
DISPLAY INVISIBLE (-5515 1785);
FORCEPROP 1 LASTPIN (-5525 1775) BN 5
J 0
(-5577 1783);
DISPLAY 0.617021 (-5577 1783);
PAINT GREEN (-5577 1783);
FORCEPROP 2 LAST CDS_LIB mstr_standard
J 0
(-5575 1775);
PAINT MONO (-5575 1775);
DISPLAY INVISIBLE (-5575 1775);
FORCEPROP 1 LAST BODY_TYPE PLUMBING
J 0
(-5575 1725);
DISPLAY 1.595745 (-5575 1725);
PAINT GREEN (-5575 1725);
DISPLAY INVISIBLE (-5575 1725);
FORCEPROP 1 LAST HDL_TAP TRUE
J 0
(-5250 1650);
DISPLAY 1.595745 (-5250 1650);
PAINT GREEN (-5250 1650);
DISPLAY INVISIBLE (-5250 1650);
FORCEPROP 1 LAST PATH I26
J 0
(-5577 1775);
DISPLAY 0.872340 (-5577 1775);
PAINT GREEN (-5577 1775);
DISPLAY INVISIBLE (-5577 1775);
FORCEADD TAP..6
(-5575 1825);
FORCEPROP 3 LASTPIN (-5525 1825) SIG_NAME M_K_DQ<6>
J 0
(-5515 1835);
DISPLAY 0.659574 (-5515 1835);
PAINT MONO (-5515 1835);
DISPLAY INVISIBLE (-5515 1835);
FORCEPROP 1 LASTPIN (-5525 1825) BN 6
J 0
(-5577 1833);
DISPLAY 0.617021 (-5577 1833);
PAINT GREEN (-5577 1833);
FORCEPROP 2 LAST CDS_LIB mstr_standard
J 0
(-5575 1825);
PAINT MONO (-5575 1825);
DISPLAY INVISIBLE (-5575 1825);
FORCEPROP 1 LAST BODY_TYPE PLUMBING
J 0
(-5575 1775);
DISPLAY 1.595745 (-5575 1775);
PAINT GREEN (-5575 1775);
DISPLAY INVISIBLE (-5575 1775);
FORCEPROP 1 LAST HDL_TAP TRUE
J 0
(-5250 1700);
DISPLAY 1.595745 (-5250 1700);
PAINT GREEN (-5250 1700);
DISPLAY INVISIBLE (-5250 1700);
FORCEPROP 1 LAST PATH I27
J 0
(-5577 1825);
DISPLAY 0.872340 (-5577 1825);
PAINT GREEN (-5577 1825);
DISPLAY INVISIBLE (-5577 1825);
FORCEADD TAP..6
(-5575 1925);
FORCEPROP 3 LASTPIN (-5525 1925) SIG_NAME M_K_DQ<8>
J 0
(-5515 1935);
DISPLAY 0.659574 (-5515 1935);
PAINT MONO (-5515 1935);
DISPLAY INVISIBLE (-5515 1935);
FORCEPROP 1 LASTPIN (-5525 1925) BN 8
J 0
(-5577 1933);
DISPLAY 0.617021 (-5577 1933);
PAINT GREEN (-5577 1933);
FORCEPROP 2 LAST CDS_LIB mstr_standard
J 0
(-5575 1925);
PAINT MONO (-5575 1925);
DISPLAY INVISIBLE (-5575 1925);
FORCEPROP 1 LAST BODY_TYPE PLUMBING
J 0
(-5575 1875);
DISPLAY 1.595745 (-5575 1875);
PAINT GREEN (-5575 1875);
DISPLAY INVISIBLE (-5575 1875);
FORCEPROP 1 LAST HDL_TAP TRUE
J 0
(-5250 1800);
DISPLAY 1.595745 (-5250 1800);
PAINT GREEN (-5250 1800);
DISPLAY INVISIBLE (-5250 1800);
FORCEPROP 1 LAST PATH I28
J 0
(-5577 1925);
DISPLAY 0.872340 (-5577 1925);
PAINT GREEN (-5577 1925);
DISPLAY INVISIBLE (-5577 1925);
FORCEADD TAP..6
(-5575 1875);
FORCEPROP 3 LASTPIN (-5525 1875) SIG_NAME M_K_DQ<7>
J 0
(-5515 1885);
DISPLAY 0.659574 (-5515 1885);
PAINT MONO (-5515 1885);
DISPLAY INVISIBLE (-5515 1885);
FORCEPROP 1 LASTPIN (-5525 1875) BN 7
J 0
(-5577 1883);
DISPLAY 0.617021 (-5577 1883);
PAINT GREEN (-5577 1883);
FORCEPROP 2 LAST CDS_LIB mstr_standard
J 0
(-5575 1875);
PAINT MONO (-5575 1875);
DISPLAY INVISIBLE (-5575 1875);
FORCEPROP 1 LAST BODY_TYPE PLUMBING
J 0
(-5575 1825);
DISPLAY 1.595745 (-5575 1825);
PAINT GREEN (-5575 1825);
DISPLAY INVISIBLE (-5575 1825);
FORCEPROP 1 LAST HDL_TAP TRUE
J 0
(-5250 1750);
DISPLAY 1.595745 (-5250 1750);
PAINT GREEN (-5250 1750);
DISPLAY INVISIBLE (-5250 1750);
FORCEPROP 1 LAST PATH I29
J 0
(-5577 1875);
DISPLAY 0.872340 (-5577 1875);
PAINT GREEN (-5577 1875);
DISPLAY INVISIBLE (-5577 1875);
FORCEADD OFFPAGE..5
(-6425 1025);
FORCEPROP 2 LAST $XR0 83 
J 0
(-6679 1025);
DISPLAY 0.638298 (-6679 1025);
PAINT MONO (-6679 1025);
FORCEPROP 2 LAST $XR1 84 
J 0
(-6769 1025);
DISPLAY 0.638298 (-6769 1025);
PAINT MONO (-6769 1025);
FORCEPROP 2 LAST CDS_LIB mstr_standard
J 0
(-6425 1025);
PAINT MONO (-6425 1025);
DISPLAY INVISIBLE (-6425 1025);
FORCEPROP 1 LAST OFFPAGE TRUE
J 0
(-6100 900);
DISPLAY 1.170213 (-6100 900);
PAINT GREEN (-6100 900);
DISPLAY INVISIBLE (-6100 900);
FORCEPROP 1 LAST COMMENT_BODY TRUE
J 0
(-6325 950);
DISPLAY 1.170213 (-6325 950);
PAINT GREEN (-6325 950);
DISPLAY INVISIBLE (-6325 950);
FORCEPROP 2 LAST PATH I3
J 0
(-6375 1100);
DISPLAY 1.021277 (-6375 1100);
PAINT ORANGE (-6375 1100);
DISPLAY INVISIBLE (-6375 1100);
FORCEADD TAP..6
(-5575 1975);
FORCEPROP 3 LASTPIN (-5525 1975) SIG_NAME M_K_DQ<9>
J 0
(-5515 1985);
DISPLAY 0.659574 (-5515 1985);
PAINT MONO (-5515 1985);
DISPLAY INVISIBLE (-5515 1985);
FORCEPROP 1 LASTPIN (-5525 1975) BN 9
J 0
(-5577 1983);
DISPLAY 0.617021 (-5577 1983);
PAINT GREEN (-5577 1983);
FORCEPROP 2 LAST CDS_LIB mstr_standard
J 0
(-5575 1975);
PAINT MONO (-5575 1975);
DISPLAY INVISIBLE (-5575 1975);
FORCEPROP 1 LAST BODY_TYPE PLUMBING
J 0
(-5575 1925);
DISPLAY 1.595745 (-5575 1925);
PAINT GREEN (-5575 1925);
DISPLAY INVISIBLE (-5575 1925);
FORCEPROP 1 LAST HDL_TAP TRUE
J 0
(-5250 1850);
DISPLAY 1.595745 (-5250 1850);
PAINT GREEN (-5250 1850);
DISPLAY INVISIBLE (-5250 1850);
FORCEPROP 1 LAST PATH I31
J 0
(-5577 1975);
DISPLAY 0.872340 (-5577 1975);
PAINT GREEN (-5577 1975);
DISPLAY INVISIBLE (-5577 1975);
FORCEADD TAP..6
(-5575 2025);
FORCEPROP 3 LASTPIN (-5525 2025) SIG_NAME M_K_DQ<10>
J 0
(-5515 2035);
DISPLAY 0.659574 (-5515 2035);
PAINT MONO (-5515 2035);
DISPLAY INVISIBLE (-5515 2035);
FORCEPROP 1 LASTPIN (-5525 2025) BN 10
J 0
(-5577 2033);
DISPLAY 0.617021 (-5577 2033);
PAINT GREEN (-5577 2033);
FORCEPROP 2 LAST CDS_LIB mstr_standard
J 0
(-5575 2025);
PAINT MONO (-5575 2025);
DISPLAY INVISIBLE (-5575 2025);
FORCEPROP 1 LAST BODY_TYPE PLUMBING
J 0
(-5575 1975);
DISPLAY 1.595745 (-5575 1975);
PAINT GREEN (-5575 1975);
DISPLAY INVISIBLE (-5575 1975);
FORCEPROP 1 LAST HDL_TAP TRUE
J 0
(-5250 1900);
DISPLAY 1.595745 (-5250 1900);
PAINT GREEN (-5250 1900);
DISPLAY INVISIBLE (-5250 1900);
FORCEPROP 1 LAST PATH I32
J 0
(-5577 2025);
DISPLAY 0.872340 (-5577 2025);
PAINT GREEN (-5577 2025);
DISPLAY INVISIBLE (-5577 2025);
FORCEADD TAP..6
(-5575 2075);
FORCEPROP 3 LASTPIN (-5525 2075) SIG_NAME M_K_DQ<11>
J 0
(-5515 2085);
DISPLAY 0.659574 (-5515 2085);
PAINT MONO (-5515 2085);
DISPLAY INVISIBLE (-5515 2085);
FORCEPROP 1 LASTPIN (-5525 2075) BN 11
J 0
(-5577 2083);
DISPLAY 0.617021 (-5577 2083);
PAINT GREEN (-5577 2083);
FORCEPROP 2 LAST CDS_LIB mstr_standard
J 0
(-5575 2075);
PAINT MONO (-5575 2075);
DISPLAY INVISIBLE (-5575 2075);
FORCEPROP 1 LAST BODY_TYPE PLUMBING
J 0
(-5575 2025);
DISPLAY 1.595745 (-5575 2025);
PAINT GREEN (-5575 2025);
DISPLAY INVISIBLE (-5575 2025);
FORCEPROP 1 LAST HDL_TAP TRUE
J 0
(-5250 1950);
DISPLAY 1.595745 (-5250 1950);
PAINT GREEN (-5250 1950);
DISPLAY INVISIBLE (-5250 1950);
FORCEPROP 1 LAST PATH I33
J 0
(-5577 2075);
DISPLAY 0.872340 (-5577 2075);
PAINT GREEN (-5577 2075);
DISPLAY INVISIBLE (-5577 2075);
FORCEADD TAP..6
(-5575 2125);
FORCEPROP 3 LASTPIN (-5525 2125) SIG_NAME M_K_DQ<12>
J 0
(-5515 2135);
DISPLAY 0.659574 (-5515 2135);
PAINT MONO (-5515 2135);
DISPLAY INVISIBLE (-5515 2135);
FORCEPROP 1 LASTPIN (-5525 2125) BN 12
J 0
(-5577 2133);
DISPLAY 0.617021 (-5577 2133);
PAINT GREEN (-5577 2133);
FORCEPROP 2 LAST CDS_LIB mstr_standard
J 0
(-5575 2125);
PAINT MONO (-5575 2125);
DISPLAY INVISIBLE (-5575 2125);
FORCEPROP 1 LAST BODY_TYPE PLUMBING
J 0
(-5575 2075);
DISPLAY 1.595745 (-5575 2075);
PAINT GREEN (-5575 2075);
DISPLAY INVISIBLE (-5575 2075);
FORCEPROP 1 LAST HDL_TAP TRUE
J 0
(-5250 2000);
DISPLAY 1.595745 (-5250 2000);
PAINT GREEN (-5250 2000);
DISPLAY INVISIBLE (-5250 2000);
FORCEPROP 1 LAST PATH I34
J 0
(-5577 2125);
DISPLAY 0.872340 (-5577 2125);
PAINT GREEN (-5577 2125);
DISPLAY INVISIBLE (-5577 2125);
FORCEADD TAP..6
(-5575 2175);
FORCEPROP 3 LASTPIN (-5525 2175) SIG_NAME M_K_DQ<13>
J 0
(-5515 2185);
DISPLAY 0.659574 (-5515 2185);
PAINT MONO (-5515 2185);
DISPLAY INVISIBLE (-5515 2185);
FORCEPROP 1 LASTPIN (-5525 2175) BN 13
J 0
(-5577 2183);
DISPLAY 0.617021 (-5577 2183);
PAINT GREEN (-5577 2183);
FORCEPROP 2 LAST CDS_LIB mstr_standard
J 0
(-5575 2175);
PAINT MONO (-5575 2175);
DISPLAY INVISIBLE (-5575 2175);
FORCEPROP 1 LAST BODY_TYPE PLUMBING
J 0
(-5575 2125);
DISPLAY 1.595745 (-5575 2125);
PAINT GREEN (-5575 2125);
DISPLAY INVISIBLE (-5575 2125);
FORCEPROP 1 LAST HDL_TAP TRUE
J 0
(-5250 2050);
DISPLAY 1.595745 (-5250 2050);
PAINT GREEN (-5250 2050);
DISPLAY INVISIBLE (-5250 2050);
FORCEPROP 1 LAST PATH I35
J 0
(-5577 2175);
DISPLAY 0.872340 (-5577 2175);
PAINT GREEN (-5577 2175);
DISPLAY INVISIBLE (-5577 2175);
FORCEADD TAP..6
(-5575 2225);
FORCEPROP 3 LASTPIN (-5525 2225) SIG_NAME M_K_DQ<14>
J 0
(-5515 2235);
DISPLAY 0.659574 (-5515 2235);
PAINT MONO (-5515 2235);
DISPLAY INVISIBLE (-5515 2235);
FORCEPROP 1 LASTPIN (-5525 2225) BN 14
J 0
(-5577 2233);
DISPLAY 0.617021 (-5577 2233);
PAINT GREEN (-5577 2233);
FORCEPROP 2 LAST CDS_LIB mstr_standard
J 0
(-5575 2225);
PAINT MONO (-5575 2225);
DISPLAY INVISIBLE (-5575 2225);
FORCEPROP 1 LAST BODY_TYPE PLUMBING
J 0
(-5575 2175);
DISPLAY 1.595745 (-5575 2175);
PAINT GREEN (-5575 2175);
DISPLAY INVISIBLE (-5575 2175);
FORCEPROP 1 LAST HDL_TAP TRUE
J 0
(-5250 2100);
DISPLAY 1.595745 (-5250 2100);
PAINT GREEN (-5250 2100);
DISPLAY INVISIBLE (-5250 2100);
FORCEPROP 1 LAST PATH I36
J 0
(-5577 2225);
DISPLAY 0.872340 (-5577 2225);
PAINT GREEN (-5577 2225);
DISPLAY INVISIBLE (-5577 2225);
FORCEADD TAP..6
(-5575 2275);
FORCEPROP 3 LASTPIN (-5525 2275) SIG_NAME M_K_DQ<15>
J 0
(-5515 2285);
DISPLAY 0.659574 (-5515 2285);
PAINT MONO (-5515 2285);
DISPLAY INVISIBLE (-5515 2285);
FORCEPROP 1 LASTPIN (-5525 2275) BN 15
J 0
(-5577 2283);
DISPLAY 0.617021 (-5577 2283);
PAINT GREEN (-5577 2283);
FORCEPROP 2 LAST CDS_LIB mstr_standard
J 0
(-5575 2275);
PAINT MONO (-5575 2275);
DISPLAY INVISIBLE (-5575 2275);
FORCEPROP 1 LAST BODY_TYPE PLUMBING
J 0
(-5575 2225);
DISPLAY 1.595745 (-5575 2225);
PAINT GREEN (-5575 2225);
DISPLAY INVISIBLE (-5575 2225);
FORCEPROP 1 LAST HDL_TAP TRUE
J 0
(-5250 2150);
DISPLAY 1.595745 (-5250 2150);
PAINT GREEN (-5250 2150);
DISPLAY INVISIBLE (-5250 2150);
FORCEPROP 1 LAST PATH I37
J 0
(-5577 2275);
DISPLAY 0.872340 (-5577 2275);
PAINT GREEN (-5577 2275);
DISPLAY INVISIBLE (-5577 2275);
FORCEADD TAP..6
(-5575 2325);
FORCEPROP 3 LASTPIN (-5525 2325) SIG_NAME M_K_DQ<16>
J 0
(-5515 2335);
DISPLAY 0.659574 (-5515 2335);
PAINT MONO (-5515 2335);
DISPLAY INVISIBLE (-5515 2335);
FORCEPROP 1 LASTPIN (-5525 2325) BN 16
J 0
(-5577 2333);
DISPLAY 0.617021 (-5577 2333);
PAINT GREEN (-5577 2333);
FORCEPROP 2 LAST CDS_LIB mstr_standard
J 0
(-5575 2325);
PAINT MONO (-5575 2325);
DISPLAY INVISIBLE (-5575 2325);
FORCEPROP 1 LAST BODY_TYPE PLUMBING
J 0
(-5575 2275);
DISPLAY 1.595745 (-5575 2275);
PAINT GREEN (-5575 2275);
DISPLAY INVISIBLE (-5575 2275);
FORCEPROP 1 LAST HDL_TAP TRUE
J 0
(-5250 2200);
DISPLAY 1.595745 (-5250 2200);
PAINT GREEN (-5250 2200);
DISPLAY INVISIBLE (-5250 2200);
FORCEPROP 1 LAST PATH I38
J 0
(-5577 2325);
DISPLAY 0.872340 (-5577 2325);
PAINT GREEN (-5577 2325);
DISPLAY INVISIBLE (-5577 2325);
FORCEADD TAP..6
(-5575 2375);
FORCEPROP 3 LASTPIN (-5525 2375) SIG_NAME M_K_DQ<17>
J 0
(-5515 2385);
DISPLAY 0.659574 (-5515 2385);
PAINT MONO (-5515 2385);
DISPLAY INVISIBLE (-5515 2385);
FORCEPROP 1 LASTPIN (-5525 2375) BN 17
J 0
(-5577 2383);
DISPLAY 0.617021 (-5577 2383);
PAINT GREEN (-5577 2383);
FORCEPROP 2 LAST CDS_LIB mstr_standard
J 0
(-5575 2375);
PAINT MONO (-5575 2375);
DISPLAY INVISIBLE (-5575 2375);
FORCEPROP 1 LAST BODY_TYPE PLUMBING
J 0
(-5575 2325);
DISPLAY 1.595745 (-5575 2325);
PAINT GREEN (-5575 2325);
DISPLAY INVISIBLE (-5575 2325);
FORCEPROP 1 LAST HDL_TAP TRUE
J 0
(-5250 2250);
DISPLAY 1.595745 (-5250 2250);
PAINT GREEN (-5250 2250);
DISPLAY INVISIBLE (-5250 2250);
FORCEPROP 1 LAST PATH I39
J 0
(-5577 2375);
DISPLAY 0.872340 (-5577 2375);
PAINT GREEN (-5577 2375);
DISPLAY INVISIBLE (-5577 2375);
FORCEADD OFFPAGE..6
(-6425 1475);
FORCEPROP 2 LAST $XR0 83 
J 0
(-6674 1475);
DISPLAY 0.638298 (-6674 1475);
PAINT MONO (-6674 1475);
FORCEPROP 2 LAST $XR1 84 
J 0
(-6764 1475);
DISPLAY 0.638298 (-6764 1475);
PAINT MONO (-6764 1475);
FORCEPROP 2 LAST CDS_LIB mstr_standard
J 0
(-6425 1475);
PAINT MONO (-6425 1475);
DISPLAY INVISIBLE (-6425 1475);
FORCEPROP 1 LAST OFFPAGE TRUE
J 0
(-6100 1350);
DISPLAY 1.170213 (-6100 1350);
PAINT GREEN (-6100 1350);
DISPLAY INVISIBLE (-6100 1350);
FORCEPROP 1 LAST COMMENT_BODY TRUE
J 0
(-6325 1400);
DISPLAY 1.170213 (-6325 1400);
PAINT GREEN (-6325 1400);
DISPLAY INVISIBLE (-6325 1400);
FORCEPROP 2 LAST PATH I4
J 0
(-6375 1550);
DISPLAY 1.021277 (-6375 1550);
PAINT ORANGE (-6375 1550);
DISPLAY INVISIBLE (-6375 1550);
FORCEADD TAP..6
(-5575 2425);
FORCEPROP 3 LASTPIN (-5525 2425) SIG_NAME M_K_DQ<18>
J 0
(-5515 2435);
DISPLAY 0.659574 (-5515 2435);
PAINT MONO (-5515 2435);
DISPLAY INVISIBLE (-5515 2435);
FORCEPROP 1 LASTPIN (-5525 2425) BN 18
J 0
(-5577 2433);
DISPLAY 0.617021 (-5577 2433);
PAINT GREEN (-5577 2433);
FORCEPROP 2 LAST CDS_LIB mstr_standard
J 0
(-5575 2425);
PAINT MONO (-5575 2425);
DISPLAY INVISIBLE (-5575 2425);
FORCEPROP 1 LAST BODY_TYPE PLUMBING
J 0
(-5575 2375);
DISPLAY 1.595745 (-5575 2375);
PAINT GREEN (-5575 2375);
DISPLAY INVISIBLE (-5575 2375);
FORCEPROP 1 LAST HDL_TAP TRUE
J 0
(-5250 2300);
DISPLAY 1.595745 (-5250 2300);
PAINT GREEN (-5250 2300);
DISPLAY INVISIBLE (-5250 2300);
FORCEPROP 1 LAST PATH I40
J 0
(-5577 2425);
DISPLAY 0.872340 (-5577 2425);
PAINT GREEN (-5577 2425);
DISPLAY INVISIBLE (-5577 2425);
FORCEADD TAP..6
(-5575 2475);
FORCEPROP 3 LASTPIN (-5525 2475) SIG_NAME M_K_DQ<19>
J 0
(-5515 2485);
DISPLAY 0.659574 (-5515 2485);
PAINT MONO (-5515 2485);
DISPLAY INVISIBLE (-5515 2485);
FORCEPROP 1 LASTPIN (-5525 2475) BN 19
J 0
(-5577 2483);
DISPLAY 0.617021 (-5577 2483);
PAINT GREEN (-5577 2483);
FORCEPROP 2 LAST CDS_LIB mstr_standard
J 0
(-5575 2475);
PAINT MONO (-5575 2475);
DISPLAY INVISIBLE (-5575 2475);
FORCEPROP 1 LAST BODY_TYPE PLUMBING
J 0
(-5575 2425);
DISPLAY 1.595745 (-5575 2425);
PAINT GREEN (-5575 2425);
DISPLAY INVISIBLE (-5575 2425);
FORCEPROP 1 LAST HDL_TAP TRUE
J 0
(-5250 2350);
DISPLAY 1.595745 (-5250 2350);
PAINT GREEN (-5250 2350);
DISPLAY INVISIBLE (-5250 2350);
FORCEPROP 1 LAST PATH I41
J 0
(-5577 2475);
DISPLAY 0.872340 (-5577 2475);
PAINT GREEN (-5577 2475);
DISPLAY INVISIBLE (-5577 2475);
FORCEADD TAP..6
(-5575 2525);
FORCEPROP 3 LASTPIN (-5525 2525) SIG_NAME M_K_DQ<20>
J 0
(-5515 2535);
DISPLAY 0.659574 (-5515 2535);
PAINT MONO (-5515 2535);
DISPLAY INVISIBLE (-5515 2535);
FORCEPROP 1 LASTPIN (-5525 2525) BN 20
J 0
(-5577 2533);
DISPLAY 0.617021 (-5577 2533);
PAINT GREEN (-5577 2533);
FORCEPROP 2 LAST CDS_LIB mstr_standard
J 0
(-5575 2525);
PAINT MONO (-5575 2525);
DISPLAY INVISIBLE (-5575 2525);
FORCEPROP 1 LAST BODY_TYPE PLUMBING
J 0
(-5575 2475);
DISPLAY 1.595745 (-5575 2475);
PAINT GREEN (-5575 2475);
DISPLAY INVISIBLE (-5575 2475);
FORCEPROP 1 LAST HDL_TAP TRUE
J 0
(-5250 2400);
DISPLAY 1.595745 (-5250 2400);
PAINT GREEN (-5250 2400);
DISPLAY INVISIBLE (-5250 2400);
FORCEPROP 1 LAST PATH I42
J 0
(-5577 2525);
DISPLAY 0.872340 (-5577 2525);
PAINT GREEN (-5577 2525);
DISPLAY INVISIBLE (-5577 2525);
FORCEADD TAP..6
(-5575 2575);
FORCEPROP 3 LASTPIN (-5525 2575) SIG_NAME M_K_DQ<21>
J 0
(-5515 2585);
DISPLAY 0.659574 (-5515 2585);
PAINT MONO (-5515 2585);
DISPLAY INVISIBLE (-5515 2585);
FORCEPROP 1 LASTPIN (-5525 2575) BN 21
J 0
(-5577 2583);
DISPLAY 0.617021 (-5577 2583);
PAINT GREEN (-5577 2583);
FORCEPROP 2 LAST CDS_LIB mstr_standard
J 0
(-5575 2575);
PAINT MONO (-5575 2575);
DISPLAY INVISIBLE (-5575 2575);
FORCEPROP 1 LAST BODY_TYPE PLUMBING
J 0
(-5575 2525);
DISPLAY 1.595745 (-5575 2525);
PAINT GREEN (-5575 2525);
DISPLAY INVISIBLE (-5575 2525);
FORCEPROP 1 LAST HDL_TAP TRUE
J 0
(-5250 2450);
DISPLAY 1.595745 (-5250 2450);
PAINT GREEN (-5250 2450);
DISPLAY INVISIBLE (-5250 2450);
FORCEPROP 1 LAST PATH I43
J 0
(-5577 2575);
DISPLAY 0.872340 (-5577 2575);
PAINT GREEN (-5577 2575);
DISPLAY INVISIBLE (-5577 2575);
FORCEADD TAP..6
(-5575 2625);
FORCEPROP 3 LASTPIN (-5525 2625) SIG_NAME M_K_DQ<22>
J 0
(-5515 2635);
DISPLAY 0.659574 (-5515 2635);
PAINT MONO (-5515 2635);
DISPLAY INVISIBLE (-5515 2635);
FORCEPROP 1 LASTPIN (-5525 2625) BN 22
J 0
(-5577 2633);
DISPLAY 0.617021 (-5577 2633);
PAINT GREEN (-5577 2633);
FORCEPROP 2 LAST CDS_LIB mstr_standard
J 0
(-5575 2625);
PAINT MONO (-5575 2625);
DISPLAY INVISIBLE (-5575 2625);
FORCEPROP 1 LAST BODY_TYPE PLUMBING
J 0
(-5575 2575);
DISPLAY 1.595745 (-5575 2575);
PAINT GREEN (-5575 2575);
DISPLAY INVISIBLE (-5575 2575);
FORCEPROP 1 LAST HDL_TAP TRUE
J 0
(-5250 2500);
DISPLAY 1.595745 (-5250 2500);
PAINT GREEN (-5250 2500);
DISPLAY INVISIBLE (-5250 2500);
FORCEPROP 1 LAST PATH I44
J 0
(-5577 2625);
DISPLAY 0.872340 (-5577 2625);
PAINT GREEN (-5577 2625);
DISPLAY INVISIBLE (-5577 2625);
FORCEADD TAP..6
(-5575 2675);
FORCEPROP 3 LASTPIN (-5525 2675) SIG_NAME M_K_DQ<23>
J 0
(-5515 2685);
DISPLAY 0.659574 (-5515 2685);
PAINT MONO (-5515 2685);
DISPLAY INVISIBLE (-5515 2685);
FORCEPROP 1 LASTPIN (-5525 2675) BN 23
J 0
(-5577 2683);
DISPLAY 0.617021 (-5577 2683);
PAINT GREEN (-5577 2683);
FORCEPROP 2 LAST CDS_LIB mstr_standard
J 0
(-5575 2675);
PAINT MONO (-5575 2675);
DISPLAY INVISIBLE (-5575 2675);
FORCEPROP 1 LAST BODY_TYPE PLUMBING
J 0
(-5575 2625);
DISPLAY 1.595745 (-5575 2625);
PAINT GREEN (-5575 2625);
DISPLAY INVISIBLE (-5575 2625);
FORCEPROP 1 LAST HDL_TAP TRUE
J 0
(-5250 2550);
DISPLAY 1.595745 (-5250 2550);
PAINT GREEN (-5250 2550);
DISPLAY INVISIBLE (-5250 2550);
FORCEPROP 1 LAST PATH I45
J 0
(-5577 2675);
DISPLAY 0.872340 (-5577 2675);
PAINT GREEN (-5577 2675);
DISPLAY INVISIBLE (-5577 2675);
FORCEADD TAP..6
(-5575 2725);
FORCEPROP 3 LASTPIN (-5525 2725) SIG_NAME M_K_DQ<24>
J 0
(-5515 2735);
DISPLAY 0.659574 (-5515 2735);
PAINT MONO (-5515 2735);
DISPLAY INVISIBLE (-5515 2735);
FORCEPROP 1 LASTPIN (-5525 2725) BN 24
J 0
(-5577 2733);
DISPLAY 0.617021 (-5577 2733);
PAINT GREEN (-5577 2733);
FORCEPROP 2 LAST CDS_LIB mstr_standard
J 0
(-5575 2725);
PAINT MONO (-5575 2725);
DISPLAY INVISIBLE (-5575 2725);
FORCEPROP 1 LAST BODY_TYPE PLUMBING
J 0
(-5575 2675);
DISPLAY 1.595745 (-5575 2675);
PAINT GREEN (-5575 2675);
DISPLAY INVISIBLE (-5575 2675);
FORCEPROP 1 LAST HDL_TAP TRUE
J 0
(-5250 2600);
DISPLAY 1.595745 (-5250 2600);
PAINT GREEN (-5250 2600);
DISPLAY INVISIBLE (-5250 2600);
FORCEPROP 1 LAST PATH I46
J 0
(-5577 2725);
DISPLAY 0.872340 (-5577 2725);
PAINT GREEN (-5577 2725);
DISPLAY INVISIBLE (-5577 2725);
FORCEADD TAP..6
(-5575 2825);
FORCEPROP 3 LASTPIN (-5525 2825) SIG_NAME M_K_DQ<26>
J 0
(-5515 2835);
DISPLAY 0.659574 (-5515 2835);
PAINT MONO (-5515 2835);
DISPLAY INVISIBLE (-5515 2835);
FORCEPROP 1 LASTPIN (-5525 2825) BN 26
J 0
(-5577 2833);
DISPLAY 0.617021 (-5577 2833);
PAINT GREEN (-5577 2833);
FORCEPROP 2 LAST CDS_LIB mstr_standard
J 0
(-5575 2825);
PAINT MONO (-5575 2825);
DISPLAY INVISIBLE (-5575 2825);
FORCEPROP 1 LAST BODY_TYPE PLUMBING
J 0
(-5575 2775);
DISPLAY 1.595745 (-5575 2775);
PAINT GREEN (-5575 2775);
DISPLAY INVISIBLE (-5575 2775);
FORCEPROP 1 LAST HDL_TAP TRUE
J 0
(-5250 2700);
DISPLAY 1.595745 (-5250 2700);
PAINT GREEN (-5250 2700);
DISPLAY INVISIBLE (-5250 2700);
FORCEPROP 1 LAST PATH I47
J 0
(-5577 2825);
DISPLAY 0.872340 (-5577 2825);
PAINT GREEN (-5577 2825);
DISPLAY INVISIBLE (-5577 2825);
FORCEADD TAP..6
(-5575 2775);
FORCEPROP 3 LASTPIN (-5525 2775) SIG_NAME M_K_DQ<25>
J 0
(-5515 2785);
DISPLAY 0.659574 (-5515 2785);
PAINT MONO (-5515 2785);
DISPLAY INVISIBLE (-5515 2785);
FORCEPROP 1 LASTPIN (-5525 2775) BN 25
J 0
(-5577 2783);
DISPLAY 0.617021 (-5577 2783);
PAINT GREEN (-5577 2783);
FORCEPROP 2 LAST CDS_LIB mstr_standard
J 0
(-5575 2775);
PAINT MONO (-5575 2775);
DISPLAY INVISIBLE (-5575 2775);
FORCEPROP 1 LAST BODY_TYPE PLUMBING
J 0
(-5575 2725);
DISPLAY 1.595745 (-5575 2725);
PAINT GREEN (-5575 2725);
DISPLAY INVISIBLE (-5575 2725);
FORCEPROP 1 LAST HDL_TAP TRUE
J 0
(-5250 2650);
DISPLAY 1.595745 (-5250 2650);
PAINT GREEN (-5250 2650);
DISPLAY INVISIBLE (-5250 2650);
FORCEPROP 1 LAST PATH I48
J 0
(-5577 2775);
DISPLAY 0.872340 (-5577 2775);
PAINT GREEN (-5577 2775);
DISPLAY INVISIBLE (-5577 2775);
FORCEADD TAP..6
(-5575 2875);
FORCEPROP 3 LASTPIN (-5525 2875) SIG_NAME M_K_DQ<27>
J 0
(-5515 2885);
DISPLAY 0.659574 (-5515 2885);
PAINT MONO (-5515 2885);
DISPLAY INVISIBLE (-5515 2885);
FORCEPROP 1 LASTPIN (-5525 2875) BN 27
J 0
(-5577 2883);
DISPLAY 0.617021 (-5577 2883);
PAINT GREEN (-5577 2883);
FORCEPROP 2 LAST CDS_LIB mstr_standard
J 0
(-5575 2875);
PAINT MONO (-5575 2875);
DISPLAY INVISIBLE (-5575 2875);
FORCEPROP 1 LAST BODY_TYPE PLUMBING
J 0
(-5575 2825);
DISPLAY 1.595745 (-5575 2825);
PAINT GREEN (-5575 2825);
DISPLAY INVISIBLE (-5575 2825);
FORCEPROP 1 LAST HDL_TAP TRUE
J 0
(-5250 2750);
DISPLAY 1.595745 (-5250 2750);
PAINT GREEN (-5250 2750);
DISPLAY INVISIBLE (-5250 2750);
FORCEPROP 1 LAST PATH I49
J 0
(-5577 2875);
DISPLAY 0.872340 (-5577 2875);
PAINT GREEN (-5577 2875);
DISPLAY INVISIBLE (-5577 2875);
FORCEADD TAP..6
(-5575 625);
FORCEPROP 3 LASTPIN (-5525 625) SIG_NAME M_K_CLK_DN<0>
J 0
(-5515 635);
DISPLAY 0.659574 (-5515 635);
PAINT MONO (-5515 635);
DISPLAY INVISIBLE (-5515 635);
FORCEPROP 1 LASTPIN (-5525 625) BN 0
J 0
(-5577 633);
DISPLAY 0.617021 (-5577 633);
PAINT GREEN (-5577 633);
FORCEPROP 2 LAST CDS_LIB mstr_standard
J 0
(-5575 625);
PAINT MONO (-5575 625);
DISPLAY INVISIBLE (-5575 625);
FORCEPROP 1 LAST BODY_TYPE PLUMBING
J 0
(-5575 575);
DISPLAY 1.595745 (-5575 575);
PAINT GREEN (-5575 575);
DISPLAY INVISIBLE (-5575 575);
FORCEPROP 1 LAST HDL_TAP TRUE
J 0
(-5250 500);
DISPLAY 1.595745 (-5250 500);
PAINT GREEN (-5250 500);
DISPLAY INVISIBLE (-5250 500);
FORCEPROP 1 LAST PATH I5
J 0
(-5577 625);
DISPLAY 0.872340 (-5577 625);
PAINT GREEN (-5577 625);
DISPLAY INVISIBLE (-5577 625);
FORCEADD TAP..6
(-5575 2925);
FORCEPROP 3 LASTPIN (-5525 2925) SIG_NAME M_K_DQ<28>
J 0
(-5515 2935);
DISPLAY 0.659574 (-5515 2935);
PAINT MONO (-5515 2935);
DISPLAY INVISIBLE (-5515 2935);
FORCEPROP 1 LASTPIN (-5525 2925) BN 28
J 0
(-5577 2933);
DISPLAY 0.617021 (-5577 2933);
PAINT GREEN (-5577 2933);
FORCEPROP 2 LAST CDS_LIB mstr_standard
J 0
(-5575 2925);
PAINT MONO (-5575 2925);
DISPLAY INVISIBLE (-5575 2925);
FORCEPROP 1 LAST BODY_TYPE PLUMBING
J 0
(-5575 2875);
DISPLAY 1.595745 (-5575 2875);
PAINT GREEN (-5575 2875);
DISPLAY INVISIBLE (-5575 2875);
FORCEPROP 1 LAST HDL_TAP TRUE
J 0
(-5250 2800);
DISPLAY 1.595745 (-5250 2800);
PAINT GREEN (-5250 2800);
DISPLAY INVISIBLE (-5250 2800);
FORCEPROP 1 LAST PATH I50
J 0
(-5577 2925);
DISPLAY 0.872340 (-5577 2925);
PAINT GREEN (-5577 2925);
DISPLAY INVISIBLE (-5577 2925);
FORCEADD TAP..6
(-5575 2975);
FORCEPROP 3 LASTPIN (-5525 2975) SIG_NAME M_K_DQ<29>
J 0
(-5515 2985);
DISPLAY 0.659574 (-5515 2985);
PAINT MONO (-5515 2985);
DISPLAY INVISIBLE (-5515 2985);
FORCEPROP 1 LASTPIN (-5525 2975) BN 29
J 0
(-5577 2983);
DISPLAY 0.617021 (-5577 2983);
PAINT GREEN (-5577 2983);
FORCEPROP 2 LAST CDS_LIB mstr_standard
J 0
(-5575 2975);
PAINT MONO (-5575 2975);
DISPLAY INVISIBLE (-5575 2975);
FORCEPROP 1 LAST BODY_TYPE PLUMBING
J 0
(-5575 2925);
DISPLAY 1.595745 (-5575 2925);
PAINT GREEN (-5575 2925);
DISPLAY INVISIBLE (-5575 2925);
FORCEPROP 1 LAST HDL_TAP TRUE
J 0
(-5250 2850);
DISPLAY 1.595745 (-5250 2850);
PAINT GREEN (-5250 2850);
DISPLAY INVISIBLE (-5250 2850);
FORCEPROP 1 LAST PATH I51
J 0
(-5577 2975);
DISPLAY 0.872340 (-5577 2975);
PAINT GREEN (-5577 2975);
DISPLAY INVISIBLE (-5577 2975);
FORCEADD TAP..6
(-5575 3075);
FORCEPROP 3 LASTPIN (-5525 3075) SIG_NAME M_K_DQ<31>
J 0
(-5515 3085);
DISPLAY 0.659574 (-5515 3085);
PAINT MONO (-5515 3085);
DISPLAY INVISIBLE (-5515 3085);
FORCEPROP 1 LASTPIN (-5525 3075) BN 31
J 0
(-5577 3083);
DISPLAY 0.617021 (-5577 3083);
PAINT GREEN (-5577 3083);
FORCEPROP 2 LAST CDS_LIB mstr_standard
J 0
(-5575 3075);
PAINT MONO (-5575 3075);
DISPLAY INVISIBLE (-5575 3075);
FORCEPROP 1 LAST BODY_TYPE PLUMBING
J 0
(-5575 3025);
DISPLAY 1.595745 (-5575 3025);
PAINT GREEN (-5575 3025);
DISPLAY INVISIBLE (-5575 3025);
FORCEPROP 1 LAST HDL_TAP TRUE
J 0
(-5250 2950);
DISPLAY 1.595745 (-5250 2950);
PAINT GREEN (-5250 2950);
DISPLAY INVISIBLE (-5250 2950);
FORCEPROP 1 LAST PATH I52
J 0
(-5577 3075);
DISPLAY 0.872340 (-5577 3075);
PAINT GREEN (-5577 3075);
DISPLAY INVISIBLE (-5577 3075);
FORCEADD TAP..6
(-5575 3025);
FORCEPROP 3 LASTPIN (-5525 3025) SIG_NAME M_K_DQ<30>
J 0
(-5515 3035);
DISPLAY 0.659574 (-5515 3035);
PAINT MONO (-5515 3035);
DISPLAY INVISIBLE (-5515 3035);
FORCEPROP 1 LASTPIN (-5525 3025) BN 30
J 0
(-5577 3033);
DISPLAY 0.617021 (-5577 3033);
PAINT GREEN (-5577 3033);
FORCEPROP 2 LAST CDS_LIB mstr_standard
J 0
(-5575 3025);
PAINT MONO (-5575 3025);
DISPLAY INVISIBLE (-5575 3025);
FORCEPROP 1 LAST BODY_TYPE PLUMBING
J 0
(-5575 2975);
DISPLAY 1.595745 (-5575 2975);
PAINT GREEN (-5575 2975);
DISPLAY INVISIBLE (-5575 2975);
FORCEPROP 1 LAST HDL_TAP TRUE
J 0
(-5250 2900);
DISPLAY 1.595745 (-5250 2900);
PAINT GREEN (-5250 2900);
DISPLAY INVISIBLE (-5250 2900);
FORCEPROP 1 LAST PATH I53
J 0
(-5577 3025);
DISPLAY 0.872340 (-5577 3025);
PAINT GREEN (-5577 3025);
DISPLAY INVISIBLE (-5577 3025);
FORCEADD TAP..6
(-5575 3125);
FORCEPROP 3 LASTPIN (-5525 3125) SIG_NAME M_K_DQ<32>
J 0
(-5515 3135);
DISPLAY 0.659574 (-5515 3135);
PAINT MONO (-5515 3135);
DISPLAY INVISIBLE (-5515 3135);
FORCEPROP 1 LASTPIN (-5525 3125) BN 32
J 0
(-5577 3133);
DISPLAY 0.617021 (-5577 3133);
PAINT GREEN (-5577 3133);
FORCEPROP 2 LAST CDS_LIB mstr_standard
J 0
(-5575 3125);
PAINT MONO (-5575 3125);
DISPLAY INVISIBLE (-5575 3125);
FORCEPROP 1 LAST BODY_TYPE PLUMBING
J 0
(-5575 3075);
DISPLAY 1.595745 (-5575 3075);
PAINT GREEN (-5575 3075);
DISPLAY INVISIBLE (-5575 3075);
FORCEPROP 1 LAST HDL_TAP TRUE
J 0
(-5250 3000);
DISPLAY 1.595745 (-5250 3000);
PAINT GREEN (-5250 3000);
DISPLAY INVISIBLE (-5250 3000);
FORCEPROP 1 LAST PATH I54
J 0
(-5577 3125);
DISPLAY 0.872340 (-5577 3125);
PAINT GREEN (-5577 3125);
DISPLAY INVISIBLE (-5577 3125);
FORCEADD TAP..6
(-5575 3175);
FORCEPROP 3 LASTPIN (-5525 3175) SIG_NAME M_K_DQ<33>
J 0
(-5515 3185);
DISPLAY 0.659574 (-5515 3185);
PAINT MONO (-5515 3185);
DISPLAY INVISIBLE (-5515 3185);
FORCEPROP 1 LASTPIN (-5525 3175) BN 33
J 0
(-5577 3183);
DISPLAY 0.617021 (-5577 3183);
PAINT GREEN (-5577 3183);
FORCEPROP 2 LAST CDS_LIB mstr_standard
J 0
(-5575 3175);
PAINT MONO (-5575 3175);
DISPLAY INVISIBLE (-5575 3175);
FORCEPROP 1 LAST BODY_TYPE PLUMBING
J 0
(-5575 3125);
DISPLAY 1.595745 (-5575 3125);
PAINT GREEN (-5575 3125);
DISPLAY INVISIBLE (-5575 3125);
FORCEPROP 1 LAST HDL_TAP TRUE
J 0
(-5250 3050);
DISPLAY 1.595745 (-5250 3050);
PAINT GREEN (-5250 3050);
DISPLAY INVISIBLE (-5250 3050);
FORCEPROP 1 LAST PATH I55
J 0
(-5577 3175);
DISPLAY 0.872340 (-5577 3175);
PAINT GREEN (-5577 3175);
DISPLAY INVISIBLE (-5577 3175);
FORCEADD TAP..6
(-5575 3225);
FORCEPROP 3 LASTPIN (-5525 3225) SIG_NAME M_K_DQ<34>
J 0
(-5515 3235);
DISPLAY 0.659574 (-5515 3235);
PAINT MONO (-5515 3235);
DISPLAY INVISIBLE (-5515 3235);
FORCEPROP 1 LASTPIN (-5525 3225) BN 34
J 0
(-5577 3233);
DISPLAY 0.617021 (-5577 3233);
PAINT GREEN (-5577 3233);
FORCEPROP 2 LAST CDS_LIB mstr_standard
J 0
(-5575 3225);
PAINT MONO (-5575 3225);
DISPLAY INVISIBLE (-5575 3225);
FORCEPROP 1 LAST BODY_TYPE PLUMBING
J 0
(-5575 3175);
DISPLAY 1.595745 (-5575 3175);
PAINT GREEN (-5575 3175);
DISPLAY INVISIBLE (-5575 3175);
FORCEPROP 1 LAST HDL_TAP TRUE
J 0
(-5250 3100);
DISPLAY 1.595745 (-5250 3100);
PAINT GREEN (-5250 3100);
DISPLAY INVISIBLE (-5250 3100);
FORCEPROP 1 LAST PATH I56
J 0
(-5577 3225);
DISPLAY 0.872340 (-5577 3225);
PAINT GREEN (-5577 3225);
DISPLAY INVISIBLE (-5577 3225);
FORCEADD TAP..6
(-5575 3325);
FORCEPROP 3 LASTPIN (-5525 3325) SIG_NAME M_K_DQ<36>
J 0
(-5515 3335);
DISPLAY 0.659574 (-5515 3335);
PAINT MONO (-5515 3335);
DISPLAY INVISIBLE (-5515 3335);
FORCEPROP 1 LASTPIN (-5525 3325) BN 36
J 0
(-5577 3333);
DISPLAY 0.617021 (-5577 3333);
PAINT GREEN (-5577 3333);
FORCEPROP 2 LAST CDS_LIB mstr_standard
J 0
(-5575 3325);
PAINT MONO (-5575 3325);
DISPLAY INVISIBLE (-5575 3325);
FORCEPROP 1 LAST BODY_TYPE PLUMBING
J 0
(-5575 3275);
DISPLAY 1.595745 (-5575 3275);
PAINT GREEN (-5575 3275);
DISPLAY INVISIBLE (-5575 3275);
FORCEPROP 1 LAST HDL_TAP TRUE
J 0
(-5250 3200);
DISPLAY 1.595745 (-5250 3200);
PAINT GREEN (-5250 3200);
DISPLAY INVISIBLE (-5250 3200);
FORCEPROP 1 LAST PATH I57
J 0
(-5577 3325);
DISPLAY 0.872340 (-5577 3325);
PAINT GREEN (-5577 3325);
DISPLAY INVISIBLE (-5577 3325);
FORCEADD TAP..6
(-5575 3275);
FORCEPROP 3 LASTPIN (-5525 3275) SIG_NAME M_K_DQ<35>
J 0
(-5515 3285);
DISPLAY 0.659574 (-5515 3285);
PAINT MONO (-5515 3285);
DISPLAY INVISIBLE (-5515 3285);
FORCEPROP 1 LASTPIN (-5525 3275) BN 35
J 0
(-5577 3283);
DISPLAY 0.617021 (-5577 3283);
PAINT GREEN (-5577 3283);
FORCEPROP 2 LAST CDS_LIB mstr_standard
J 0
(-5575 3275);
PAINT MONO (-5575 3275);
DISPLAY INVISIBLE (-5575 3275);
FORCEPROP 1 LAST BODY_TYPE PLUMBING
J 0
(-5575 3225);
DISPLAY 1.595745 (-5575 3225);
PAINT GREEN (-5575 3225);
DISPLAY INVISIBLE (-5575 3225);
FORCEPROP 1 LAST HDL_TAP TRUE
J 0
(-5250 3150);
DISPLAY 1.595745 (-5250 3150);
PAINT GREEN (-5250 3150);
DISPLAY INVISIBLE (-5250 3150);
FORCEPROP 1 LAST PATH I58
J 0
(-5577 3275);
DISPLAY 0.872340 (-5577 3275);
PAINT GREEN (-5577 3275);
DISPLAY INVISIBLE (-5577 3275);
FORCEADD TAP..6
(-5575 3375);
FORCEPROP 3 LASTPIN (-5525 3375) SIG_NAME M_K_DQ<37>
J 0
(-5515 3385);
DISPLAY 0.659574 (-5515 3385);
PAINT MONO (-5515 3385);
DISPLAY INVISIBLE (-5515 3385);
FORCEPROP 1 LASTPIN (-5525 3375) BN 37
J 0
(-5577 3383);
DISPLAY 0.617021 (-5577 3383);
PAINT GREEN (-5577 3383);
FORCEPROP 2 LAST CDS_LIB mstr_standard
J 0
(-5575 3375);
PAINT MONO (-5575 3375);
DISPLAY INVISIBLE (-5575 3375);
FORCEPROP 1 LAST BODY_TYPE PLUMBING
J 0
(-5575 3325);
DISPLAY 1.595745 (-5575 3325);
PAINT GREEN (-5575 3325);
DISPLAY INVISIBLE (-5575 3325);
FORCEPROP 1 LAST HDL_TAP TRUE
J 0
(-5250 3250);
DISPLAY 1.595745 (-5250 3250);
PAINT GREEN (-5250 3250);
DISPLAY INVISIBLE (-5250 3250);
FORCEPROP 1 LAST PATH I59
J 0
(-5577 3375);
DISPLAY 0.872340 (-5577 3375);
PAINT GREEN (-5577 3375);
DISPLAY INVISIBLE (-5577 3375);
FORCEADD TAP..6
(-5575 675);
FORCEPROP 3 LASTPIN (-5525 675) SIG_NAME M_K_CLK_DN<1>
J 0
(-5515 685);
DISPLAY 0.659574 (-5515 685);
PAINT MONO (-5515 685);
DISPLAY INVISIBLE (-5515 685);
FORCEPROP 1 LASTPIN (-5525 675) BN 1
J 0
(-5577 683);
DISPLAY 0.617021 (-5577 683);
PAINT GREEN (-5577 683);
FORCEPROP 2 LAST CDS_LIB mstr_standard
J 0
(-5575 675);
PAINT MONO (-5575 675);
DISPLAY INVISIBLE (-5575 675);
FORCEPROP 1 LAST BODY_TYPE PLUMBING
J 0
(-5575 625);
DISPLAY 1.595745 (-5575 625);
PAINT GREEN (-5575 625);
DISPLAY INVISIBLE (-5575 625);
FORCEPROP 1 LAST HDL_TAP TRUE
J 0
(-5250 550);
DISPLAY 1.595745 (-5250 550);
PAINT GREEN (-5250 550);
DISPLAY INVISIBLE (-5250 550);
FORCEPROP 1 LAST PATH I6
J 0
(-5577 675);
DISPLAY 0.872340 (-5577 675);
PAINT GREEN (-5577 675);
DISPLAY INVISIBLE (-5577 675);
FORCEADD TAP..6
(-5575 3425);
FORCEPROP 3 LASTPIN (-5525 3425) SIG_NAME M_K_DQ<38>
J 0
(-5515 3435);
DISPLAY 0.659574 (-5515 3435);
PAINT MONO (-5515 3435);
DISPLAY INVISIBLE (-5515 3435);
FORCEPROP 1 LASTPIN (-5525 3425) BN 38
J 0
(-5577 3433);
DISPLAY 0.617021 (-5577 3433);
PAINT GREEN (-5577 3433);
FORCEPROP 2 LAST CDS_LIB mstr_standard
J 0
(-5575 3425);
PAINT MONO (-5575 3425);
DISPLAY INVISIBLE (-5575 3425);
FORCEPROP 1 LAST BODY_TYPE PLUMBING
J 0
(-5575 3375);
DISPLAY 1.595745 (-5575 3375);
PAINT GREEN (-5575 3375);
DISPLAY INVISIBLE (-5575 3375);
FORCEPROP 1 LAST HDL_TAP TRUE
J 0
(-5250 3300);
DISPLAY 1.595745 (-5250 3300);
PAINT GREEN (-5250 3300);
DISPLAY INVISIBLE (-5250 3300);
FORCEPROP 1 LAST PATH I60
J 0
(-5577 3425);
DISPLAY 0.872340 (-5577 3425);
PAINT GREEN (-5577 3425);
DISPLAY INVISIBLE (-5577 3425);
FORCEADD TAP..6
(-5575 3475);
FORCEPROP 3 LASTPIN (-5525 3475) SIG_NAME M_K_DQ<39>
J 0
(-5515 3485);
DISPLAY 0.659574 (-5515 3485);
PAINT MONO (-5515 3485);
DISPLAY INVISIBLE (-5515 3485);
FORCEPROP 1 LASTPIN (-5525 3475) BN 39
J 0
(-5577 3483);
DISPLAY 0.617021 (-5577 3483);
PAINT GREEN (-5577 3483);
FORCEPROP 2 LAST CDS_LIB mstr_standard
J 0
(-5575 3475);
PAINT MONO (-5575 3475);
DISPLAY INVISIBLE (-5575 3475);
FORCEPROP 1 LAST BODY_TYPE PLUMBING
J 0
(-5575 3425);
DISPLAY 1.595745 (-5575 3425);
PAINT GREEN (-5575 3425);
DISPLAY INVISIBLE (-5575 3425);
FORCEPROP 1 LAST HDL_TAP TRUE
J 0
(-5250 3350);
DISPLAY 1.595745 (-5250 3350);
PAINT GREEN (-5250 3350);
DISPLAY INVISIBLE (-5250 3350);
FORCEPROP 1 LAST PATH I61
J 0
(-5577 3475);
DISPLAY 0.872340 (-5577 3475);
PAINT GREEN (-5577 3475);
DISPLAY INVISIBLE (-5577 3475);
FORCEADD TAP..6
(-5575 3525);
FORCEPROP 3 LASTPIN (-5525 3525) SIG_NAME M_K_DQ<40>
J 0
(-5515 3535);
DISPLAY 0.659574 (-5515 3535);
PAINT MONO (-5515 3535);
DISPLAY INVISIBLE (-5515 3535);
FORCEPROP 1 LASTPIN (-5525 3525) BN 40
J 0
(-5577 3533);
DISPLAY 0.617021 (-5577 3533);
PAINT GREEN (-5577 3533);
FORCEPROP 2 LAST CDS_LIB mstr_standard
J 0
(-5575 3525);
PAINT MONO (-5575 3525);
DISPLAY INVISIBLE (-5575 3525);
FORCEPROP 1 LAST BODY_TYPE PLUMBING
J 0
(-5575 3475);
DISPLAY 1.595745 (-5575 3475);
PAINT GREEN (-5575 3475);
DISPLAY INVISIBLE (-5575 3475);
FORCEPROP 1 LAST HDL_TAP TRUE
J 0
(-5250 3400);
DISPLAY 1.595745 (-5250 3400);
PAINT GREEN (-5250 3400);
DISPLAY INVISIBLE (-5250 3400);
FORCEPROP 1 LAST PATH I62
J 0
(-5577 3525);
DISPLAY 0.872340 (-5577 3525);
PAINT GREEN (-5577 3525);
DISPLAY INVISIBLE (-5577 3525);
FORCEADD TAP..6
(-5575 3575);
FORCEPROP 3 LASTPIN (-5525 3575) SIG_NAME M_K_DQ<41>
J 0
(-5515 3585);
DISPLAY 0.659574 (-5515 3585);
PAINT MONO (-5515 3585);
DISPLAY INVISIBLE (-5515 3585);
FORCEPROP 1 LASTPIN (-5525 3575) BN 41
J 0
(-5577 3583);
DISPLAY 0.617021 (-5577 3583);
PAINT GREEN (-5577 3583);
FORCEPROP 2 LAST CDS_LIB mstr_standard
J 0
(-5575 3575);
PAINT MONO (-5575 3575);
DISPLAY INVISIBLE (-5575 3575);
FORCEPROP 1 LAST BODY_TYPE PLUMBING
J 0
(-5575 3525);
DISPLAY 1.595745 (-5575 3525);
PAINT GREEN (-5575 3525);
DISPLAY INVISIBLE (-5575 3525);
FORCEPROP 1 LAST HDL_TAP TRUE
J 0
(-5250 3450);
DISPLAY 1.595745 (-5250 3450);
PAINT GREEN (-5250 3450);
DISPLAY INVISIBLE (-5250 3450);
FORCEPROP 1 LAST PATH I63
J 0
(-5577 3575);
DISPLAY 0.872340 (-5577 3575);
PAINT GREEN (-5577 3575);
DISPLAY INVISIBLE (-5577 3575);
FORCEADD TAP..6
(-5575 3625);
FORCEPROP 3 LASTPIN (-5525 3625) SIG_NAME M_K_DQ<42>
J 0
(-5515 3635);
DISPLAY 0.659574 (-5515 3635);
PAINT MONO (-5515 3635);
DISPLAY INVISIBLE (-5515 3635);
FORCEPROP 1 LASTPIN (-5525 3625) BN 42
J 0
(-5577 3633);
DISPLAY 0.617021 (-5577 3633);
PAINT GREEN (-5577 3633);
FORCEPROP 2 LAST CDS_LIB mstr_standard
J 0
(-5575 3625);
PAINT MONO (-5575 3625);
DISPLAY INVISIBLE (-5575 3625);
FORCEPROP 1 LAST BODY_TYPE PLUMBING
J 0
(-5575 3575);
DISPLAY 1.595745 (-5575 3575);
PAINT GREEN (-5575 3575);
DISPLAY INVISIBLE (-5575 3575);
FORCEPROP 1 LAST HDL_TAP TRUE
J 0
(-5250 3500);
DISPLAY 1.595745 (-5250 3500);
PAINT GREEN (-5250 3500);
DISPLAY INVISIBLE (-5250 3500);
FORCEPROP 1 LAST PATH I64
J 0
(-5577 3625);
DISPLAY 0.872340 (-5577 3625);
PAINT GREEN (-5577 3625);
DISPLAY INVISIBLE (-5577 3625);
FORCEADD TAP..6
(-5575 3675);
FORCEPROP 3 LASTPIN (-5525 3675) SIG_NAME M_K_DQ<43>
J 0
(-5515 3685);
DISPLAY 0.659574 (-5515 3685);
PAINT MONO (-5515 3685);
DISPLAY INVISIBLE (-5515 3685);
FORCEPROP 1 LASTPIN (-5525 3675) BN 43
J 0
(-5577 3683);
DISPLAY 0.617021 (-5577 3683);
PAINT GREEN (-5577 3683);
FORCEPROP 2 LAST CDS_LIB mstr_standard
J 0
(-5575 3675);
PAINT MONO (-5575 3675);
DISPLAY INVISIBLE (-5575 3675);
FORCEPROP 1 LAST BODY_TYPE PLUMBING
J 0
(-5575 3625);
DISPLAY 1.595745 (-5575 3625);
PAINT GREEN (-5575 3625);
DISPLAY INVISIBLE (-5575 3625);
FORCEPROP 1 LAST HDL_TAP TRUE
J 0
(-5250 3550);
DISPLAY 1.595745 (-5250 3550);
PAINT GREEN (-5250 3550);
DISPLAY INVISIBLE (-5250 3550);
FORCEPROP 1 LAST PATH I65
J 0
(-5577 3675);
DISPLAY 0.872340 (-5577 3675);
PAINT GREEN (-5577 3675);
DISPLAY INVISIBLE (-5577 3675);
FORCEADD TAP..6
(-5575 3725);
FORCEPROP 3 LASTPIN (-5525 3725) SIG_NAME M_K_DQ<44>
J 0
(-5515 3735);
DISPLAY 0.659574 (-5515 3735);
PAINT MONO (-5515 3735);
DISPLAY INVISIBLE (-5515 3735);
FORCEPROP 1 LASTPIN (-5525 3725) BN 44
J 0
(-5577 3733);
DISPLAY 0.617021 (-5577 3733);
PAINT GREEN (-5577 3733);
FORCEPROP 2 LAST CDS_LIB mstr_standard
J 0
(-5575 3725);
PAINT MONO (-5575 3725);
DISPLAY INVISIBLE (-5575 3725);
FORCEPROP 1 LAST BODY_TYPE PLUMBING
J 0
(-5575 3675);
DISPLAY 1.595745 (-5575 3675);
PAINT GREEN (-5575 3675);
DISPLAY INVISIBLE (-5575 3675);
FORCEPROP 1 LAST HDL_TAP TRUE
J 0
(-5250 3600);
DISPLAY 1.595745 (-5250 3600);
PAINT GREEN (-5250 3600);
DISPLAY INVISIBLE (-5250 3600);
FORCEPROP 1 LAST PATH I66
J 0
(-5577 3725);
DISPLAY 0.872340 (-5577 3725);
PAINT GREEN (-5577 3725);
DISPLAY INVISIBLE (-5577 3725);
FORCEADD TAP..6
(-5575 3775);
FORCEPROP 3 LASTPIN (-5525 3775) SIG_NAME M_K_DQ<45>
J 0
(-5515 3785);
DISPLAY 0.659574 (-5515 3785);
PAINT MONO (-5515 3785);
DISPLAY INVISIBLE (-5515 3785);
FORCEPROP 1 LASTPIN (-5525 3775) BN 45
J 0
(-5577 3783);
DISPLAY 0.617021 (-5577 3783);
PAINT GREEN (-5577 3783);
FORCEPROP 2 LAST CDS_LIB mstr_standard
J 0
(-5575 3775);
PAINT MONO (-5575 3775);
DISPLAY INVISIBLE (-5575 3775);
FORCEPROP 1 LAST BODY_TYPE PLUMBING
J 0
(-5575 3725);
DISPLAY 1.595745 (-5575 3725);
PAINT GREEN (-5575 3725);
DISPLAY INVISIBLE (-5575 3725);
FORCEPROP 1 LAST HDL_TAP TRUE
J 0
(-5250 3650);
DISPLAY 1.595745 (-5250 3650);
PAINT GREEN (-5250 3650);
DISPLAY INVISIBLE (-5250 3650);
FORCEPROP 1 LAST PATH I67
J 0
(-5577 3775);
DISPLAY 0.872340 (-5577 3775);
PAINT GREEN (-5577 3775);
DISPLAY INVISIBLE (-5577 3775);
FORCEADD TAP..6
(-5575 3825);
FORCEPROP 3 LASTPIN (-5525 3825) SIG_NAME M_K_DQ<46>
J 0
(-5515 3835);
DISPLAY 0.659574 (-5515 3835);
PAINT MONO (-5515 3835);
DISPLAY INVISIBLE (-5515 3835);
FORCEPROP 1 LASTPIN (-5525 3825) BN 46
J 0
(-5577 3833);
DISPLAY 0.617021 (-5577 3833);
PAINT GREEN (-5577 3833);
FORCEPROP 2 LAST CDS_LIB mstr_standard
J 0
(-5575 3825);
PAINT MONO (-5575 3825);
DISPLAY INVISIBLE (-5575 3825);
FORCEPROP 1 LAST BODY_TYPE PLUMBING
J 0
(-5575 3775);
DISPLAY 1.595745 (-5575 3775);
PAINT GREEN (-5575 3775);
DISPLAY INVISIBLE (-5575 3775);
FORCEPROP 1 LAST HDL_TAP TRUE
J 0
(-5250 3700);
DISPLAY 1.595745 (-5250 3700);
PAINT GREEN (-5250 3700);
DISPLAY INVISIBLE (-5250 3700);
FORCEPROP 1 LAST PATH I68
J 0
(-5577 3825);
DISPLAY 0.872340 (-5577 3825);
PAINT GREEN (-5577 3825);
DISPLAY INVISIBLE (-5577 3825);
FORCEADD TAP..6
(-5575 3875);
FORCEPROP 3 LASTPIN (-5525 3875) SIG_NAME M_K_DQ<47>
J 0
(-5515 3885);
DISPLAY 0.659574 (-5515 3885);
PAINT MONO (-5515 3885);
DISPLAY INVISIBLE (-5515 3885);
FORCEPROP 1 LASTPIN (-5525 3875) BN 47
J 0
(-5577 3883);
DISPLAY 0.617021 (-5577 3883);
PAINT GREEN (-5577 3883);
FORCEPROP 2 LAST CDS_LIB mstr_standard
J 0
(-5575 3875);
PAINT MONO (-5575 3875);
DISPLAY INVISIBLE (-5575 3875);
FORCEPROP 1 LAST BODY_TYPE PLUMBING
J 0
(-5575 3825);
DISPLAY 1.595745 (-5575 3825);
PAINT GREEN (-5575 3825);
DISPLAY INVISIBLE (-5575 3825);
FORCEPROP 1 LAST HDL_TAP TRUE
J 0
(-5250 3750);
DISPLAY 1.595745 (-5250 3750);
PAINT GREEN (-5250 3750);
DISPLAY INVISIBLE (-5250 3750);
FORCEPROP 1 LAST PATH I69
J 0
(-5577 3875);
DISPLAY 0.872340 (-5577 3875);
PAINT GREEN (-5577 3875);
DISPLAY INVISIBLE (-5577 3875);
FORCEADD TAP..6
(-5575 775);
FORCEPROP 3 LASTPIN (-5525 775) SIG_NAME M_K_CLK_DN<3>
J 0
(-5515 785);
DISPLAY 0.659574 (-5515 785);
PAINT MONO (-5515 785);
DISPLAY INVISIBLE (-5515 785);
FORCEPROP 1 LASTPIN (-5525 775) BN 3
J 0
(-5577 783);
DISPLAY 0.617021 (-5577 783);
PAINT GREEN (-5577 783);
FORCEPROP 2 LAST CDS_LIB mstr_standard
J 0
(-5575 775);
PAINT MONO (-5575 775);
DISPLAY INVISIBLE (-5575 775);
FORCEPROP 1 LAST BODY_TYPE PLUMBING
J 0
(-5575 725);
DISPLAY 1.595745 (-5575 725);
PAINT GREEN (-5575 725);
DISPLAY INVISIBLE (-5575 725);
FORCEPROP 1 LAST HDL_TAP TRUE
J 0
(-5250 650);
DISPLAY 1.595745 (-5250 650);
PAINT GREEN (-5250 650);
DISPLAY INVISIBLE (-5250 650);
FORCEPROP 1 LAST PATH I7
J 0
(-5577 775);
DISPLAY 0.872340 (-5577 775);
PAINT GREEN (-5577 775);
DISPLAY INVISIBLE (-5577 775);
FORCEADD TAP..6
(-5575 3925);
FORCEPROP 3 LASTPIN (-5525 3925) SIG_NAME M_K_DQ<48>
J 0
(-5515 3935);
DISPLAY 0.659574 (-5515 3935);
PAINT MONO (-5515 3935);
DISPLAY INVISIBLE (-5515 3935);
FORCEPROP 1 LASTPIN (-5525 3925) BN 48
J 0
(-5577 3933);
DISPLAY 0.617021 (-5577 3933);
PAINT GREEN (-5577 3933);
FORCEPROP 2 LAST CDS_LIB mstr_standard
J 0
(-5575 3925);
PAINT MONO (-5575 3925);
DISPLAY INVISIBLE (-5575 3925);
FORCEPROP 1 LAST BODY_TYPE PLUMBING
J 0
(-5575 3875);
DISPLAY 1.595745 (-5575 3875);
PAINT GREEN (-5575 3875);
DISPLAY INVISIBLE (-5575 3875);
FORCEPROP 1 LAST HDL_TAP TRUE
J 0
(-5250 3800);
DISPLAY 1.595745 (-5250 3800);
PAINT GREEN (-5250 3800);
DISPLAY INVISIBLE (-5250 3800);
FORCEPROP 1 LAST PATH I70
J 0
(-5577 3925);
DISPLAY 0.872340 (-5577 3925);
PAINT GREEN (-5577 3925);
DISPLAY INVISIBLE (-5577 3925);
FORCEADD TAP..6
(-5575 3975);
FORCEPROP 3 LASTPIN (-5525 3975) SIG_NAME M_K_DQ<49>
J 0
(-5515 3985);
DISPLAY 0.659574 (-5515 3985);
PAINT MONO (-5515 3985);
DISPLAY INVISIBLE (-5515 3985);
FORCEPROP 1 LASTPIN (-5525 3975) BN 49
J 0
(-5577 3983);
DISPLAY 0.617021 (-5577 3983);
PAINT GREEN (-5577 3983);
FORCEPROP 2 LAST CDS_LIB mstr_standard
J 0
(-5575 3975);
PAINT MONO (-5575 3975);
DISPLAY INVISIBLE (-5575 3975);
FORCEPROP 1 LAST BODY_TYPE PLUMBING
J 0
(-5575 3925);
DISPLAY 1.595745 (-5575 3925);
PAINT GREEN (-5575 3925);
DISPLAY INVISIBLE (-5575 3925);
FORCEPROP 1 LAST HDL_TAP TRUE
J 0
(-5250 3850);
DISPLAY 1.595745 (-5250 3850);
PAINT GREEN (-5250 3850);
DISPLAY INVISIBLE (-5250 3850);
FORCEPROP 1 LAST PATH I71
J 0
(-5577 3975);
DISPLAY 0.872340 (-5577 3975);
PAINT GREEN (-5577 3975);
DISPLAY INVISIBLE (-5577 3975);
FORCEADD OFFPAGE..6
(-6425 4800);
FORCEPROP 2 LAST $XR0 83 
J 0
(-6674 4800);
DISPLAY 0.638298 (-6674 4800);
PAINT MONO (-6674 4800);
FORCEPROP 2 LAST $XR1 84 
J 0
(-6764 4800);
DISPLAY 0.638298 (-6764 4800);
PAINT MONO (-6764 4800);
FORCEPROP 2 LAST CDS_LIB mstr_standard
J 0
(-6425 4800);
PAINT MONO (-6425 4800);
DISPLAY INVISIBLE (-6425 4800);
FORCEPROP 1 LAST OFFPAGE TRUE
J 0
(-6100 4675);
DISPLAY 1.170213 (-6100 4675);
PAINT GREEN (-6100 4675);
DISPLAY INVISIBLE (-6100 4675);
FORCEPROP 1 LAST COMMENT_BODY TRUE
J 0
(-6325 4725);
DISPLAY 1.170213 (-6325 4725);
PAINT GREEN (-6325 4725);
DISPLAY INVISIBLE (-6325 4725);
FORCEPROP 2 LAST PATH I72
J 0
(-6375 4875);
DISPLAY 1.021277 (-6375 4875);
PAINT ORANGE (-6375 4875);
DISPLAY INVISIBLE (-6375 4875);
FORCEADD TAP..6
(-5575 4025);
FORCEPROP 3 LASTPIN (-5525 4025) SIG_NAME M_K_DQ<50>
J 0
(-5515 4035);
DISPLAY 0.659574 (-5515 4035);
PAINT MONO (-5515 4035);
DISPLAY INVISIBLE (-5515 4035);
FORCEPROP 1 LASTPIN (-5525 4025) BN 50
J 0
(-5577 4033);
DISPLAY 0.617021 (-5577 4033);
PAINT GREEN (-5577 4033);
FORCEPROP 2 LAST CDS_LIB mstr_standard
J 0
(-5575 4025);
PAINT MONO (-5575 4025);
DISPLAY INVISIBLE (-5575 4025);
FORCEPROP 1 LAST BODY_TYPE PLUMBING
J 0
(-5575 3975);
DISPLAY 1.595745 (-5575 3975);
PAINT GREEN (-5575 3975);
DISPLAY INVISIBLE (-5575 3975);
FORCEPROP 1 LAST HDL_TAP TRUE
J 0
(-5250 3900);
DISPLAY 1.595745 (-5250 3900);
PAINT GREEN (-5250 3900);
DISPLAY INVISIBLE (-5250 3900);
FORCEPROP 1 LAST PATH I73
J 0
(-5577 4025);
DISPLAY 0.872340 (-5577 4025);
PAINT GREEN (-5577 4025);
DISPLAY INVISIBLE (-5577 4025);
FORCEADD TAP..6
(-5575 4075);
FORCEPROP 3 LASTPIN (-5525 4075) SIG_NAME M_K_DQ<51>
J 0
(-5515 4085);
DISPLAY 0.659574 (-5515 4085);
PAINT MONO (-5515 4085);
DISPLAY INVISIBLE (-5515 4085);
FORCEPROP 1 LASTPIN (-5525 4075) BN 51
J 0
(-5577 4083);
DISPLAY 0.617021 (-5577 4083);
PAINT GREEN (-5577 4083);
FORCEPROP 2 LAST CDS_LIB mstr_standard
J 0
(-5575 4075);
PAINT MONO (-5575 4075);
DISPLAY INVISIBLE (-5575 4075);
FORCEPROP 1 LAST BODY_TYPE PLUMBING
J 0
(-5575 4025);
DISPLAY 1.595745 (-5575 4025);
PAINT GREEN (-5575 4025);
DISPLAY INVISIBLE (-5575 4025);
FORCEPROP 1 LAST HDL_TAP TRUE
J 0
(-5250 3950);
DISPLAY 1.595745 (-5250 3950);
PAINT GREEN (-5250 3950);
DISPLAY INVISIBLE (-5250 3950);
FORCEPROP 1 LAST PATH I74
J 0
(-5577 4075);
DISPLAY 0.872340 (-5577 4075);
PAINT GREEN (-5577 4075);
DISPLAY INVISIBLE (-5577 4075);
FORCEADD TAP..6
(-5575 4125);
FORCEPROP 3 LASTPIN (-5525 4125) SIG_NAME M_K_DQ<52>
J 0
(-5515 4135);
DISPLAY 0.659574 (-5515 4135);
PAINT MONO (-5515 4135);
DISPLAY INVISIBLE (-5515 4135);
FORCEPROP 1 LASTPIN (-5525 4125) BN 52
J 0
(-5577 4133);
DISPLAY 0.617021 (-5577 4133);
PAINT GREEN (-5577 4133);
FORCEPROP 2 LAST CDS_LIB mstr_standard
J 0
(-5575 4125);
PAINT MONO (-5575 4125);
DISPLAY INVISIBLE (-5575 4125);
FORCEPROP 1 LAST BODY_TYPE PLUMBING
J 0
(-5575 4075);
DISPLAY 1.595745 (-5575 4075);
PAINT GREEN (-5575 4075);
DISPLAY INVISIBLE (-5575 4075);
FORCEPROP 1 LAST HDL_TAP TRUE
J 0
(-5250 4000);
DISPLAY 1.595745 (-5250 4000);
PAINT GREEN (-5250 4000);
DISPLAY INVISIBLE (-5250 4000);
FORCEPROP 1 LAST PATH I75
J 0
(-5577 4125);
DISPLAY 0.872340 (-5577 4125);
PAINT GREEN (-5577 4125);
DISPLAY INVISIBLE (-5577 4125);
FORCEADD TAP..6
(-5575 4175);
FORCEPROP 3 LASTPIN (-5525 4175) SIG_NAME M_K_DQ<53>
J 0
(-5515 4185);
DISPLAY 0.659574 (-5515 4185);
PAINT MONO (-5515 4185);
DISPLAY INVISIBLE (-5515 4185);
FORCEPROP 1 LASTPIN (-5525 4175) BN 53
J 0
(-5577 4183);
DISPLAY 0.617021 (-5577 4183);
PAINT GREEN (-5577 4183);
FORCEPROP 2 LAST CDS_LIB mstr_standard
J 0
(-5575 4175);
PAINT MONO (-5575 4175);
DISPLAY INVISIBLE (-5575 4175);
FORCEPROP 1 LAST BODY_TYPE PLUMBING
J 0
(-5575 4125);
DISPLAY 1.595745 (-5575 4125);
PAINT GREEN (-5575 4125);
DISPLAY INVISIBLE (-5575 4125);
FORCEPROP 1 LAST HDL_TAP TRUE
J 0
(-5250 4050);
DISPLAY 1.595745 (-5250 4050);
PAINT GREEN (-5250 4050);
DISPLAY INVISIBLE (-5250 4050);
FORCEPROP 1 LAST PATH I76
J 0
(-5577 4175);
DISPLAY 0.872340 (-5577 4175);
PAINT GREEN (-5577 4175);
DISPLAY INVISIBLE (-5577 4175);
FORCEADD TAP..6
(-5575 4225);
FORCEPROP 3 LASTPIN (-5525 4225) SIG_NAME M_K_DQ<54>
J 0
(-5515 4235);
DISPLAY 0.659574 (-5515 4235);
PAINT MONO (-5515 4235);
DISPLAY INVISIBLE (-5515 4235);
FORCEPROP 1 LASTPIN (-5525 4225) BN 54
J 0
(-5577 4233);
DISPLAY 0.617021 (-5577 4233);
PAINT GREEN (-5577 4233);
FORCEPROP 2 LAST CDS_LIB mstr_standard
J 0
(-5575 4225);
PAINT MONO (-5575 4225);
DISPLAY INVISIBLE (-5575 4225);
FORCEPROP 1 LAST BODY_TYPE PLUMBING
J 0
(-5575 4175);
DISPLAY 1.595745 (-5575 4175);
PAINT GREEN (-5575 4175);
DISPLAY INVISIBLE (-5575 4175);
FORCEPROP 1 LAST HDL_TAP TRUE
J 0
(-5250 4100);
DISPLAY 1.595745 (-5250 4100);
PAINT GREEN (-5250 4100);
DISPLAY INVISIBLE (-5250 4100);
FORCEPROP 1 LAST PATH I77
J 0
(-5577 4225);
DISPLAY 0.872340 (-5577 4225);
PAINT GREEN (-5577 4225);
DISPLAY INVISIBLE (-5577 4225);
FORCEADD TAP..6
(-5575 4275);
FORCEPROP 3 LASTPIN (-5525 4275) SIG_NAME M_K_DQ<55>
J 0
(-5515 4285);
DISPLAY 0.659574 (-5515 4285);
PAINT MONO (-5515 4285);
DISPLAY INVISIBLE (-5515 4285);
FORCEPROP 1 LASTPIN (-5525 4275) BN 55
J 0
(-5577 4283);
DISPLAY 0.617021 (-5577 4283);
PAINT GREEN (-5577 4283);
FORCEPROP 2 LAST CDS_LIB mstr_standard
J 0
(-5575 4275);
PAINT MONO (-5575 4275);
DISPLAY INVISIBLE (-5575 4275);
FORCEPROP 1 LAST BODY_TYPE PLUMBING
J 0
(-5575 4225);
DISPLAY 1.595745 (-5575 4225);
PAINT GREEN (-5575 4225);
DISPLAY INVISIBLE (-5575 4225);
FORCEPROP 1 LAST HDL_TAP TRUE
J 0
(-5250 4150);
DISPLAY 1.595745 (-5250 4150);
PAINT GREEN (-5250 4150);
DISPLAY INVISIBLE (-5250 4150);
FORCEPROP 1 LAST PATH I78
J 0
(-5577 4275);
DISPLAY 0.872340 (-5577 4275);
PAINT GREEN (-5577 4275);
DISPLAY INVISIBLE (-5577 4275);
FORCEADD TAP..6
(-5575 4325);
FORCEPROP 3 LASTPIN (-5525 4325) SIG_NAME M_K_DQ<56>
J 0
(-5515 4335);
DISPLAY 0.659574 (-5515 4335);
PAINT MONO (-5515 4335);
DISPLAY INVISIBLE (-5515 4335);
FORCEPROP 1 LASTPIN (-5525 4325) BN 56
J 0
(-5577 4333);
DISPLAY 0.617021 (-5577 4333);
PAINT GREEN (-5577 4333);
FORCEPROP 2 LAST CDS_LIB mstr_standard
J 0
(-5575 4325);
PAINT MONO (-5575 4325);
DISPLAY INVISIBLE (-5575 4325);
FORCEPROP 1 LAST BODY_TYPE PLUMBING
J 0
(-5575 4275);
DISPLAY 1.595745 (-5575 4275);
PAINT GREEN (-5575 4275);
DISPLAY INVISIBLE (-5575 4275);
FORCEPROP 1 LAST HDL_TAP TRUE
J 0
(-5250 4200);
DISPLAY 1.595745 (-5250 4200);
PAINT GREEN (-5250 4200);
DISPLAY INVISIBLE (-5250 4200);
FORCEPROP 1 LAST PATH I79
J 0
(-5577 4325);
DISPLAY 0.872340 (-5577 4325);
PAINT GREEN (-5577 4325);
DISPLAY INVISIBLE (-5577 4325);
FORCEADD TAP..6
(-5575 725);
FORCEPROP 3 LASTPIN (-5525 725) SIG_NAME M_K_CLK_DN<2>
J 0
(-5515 735);
DISPLAY 0.659574 (-5515 735);
PAINT MONO (-5515 735);
DISPLAY INVISIBLE (-5515 735);
FORCEPROP 1 LASTPIN (-5525 725) BN 2
J 0
(-5577 733);
DISPLAY 0.617021 (-5577 733);
PAINT GREEN (-5577 733);
FORCEPROP 2 LAST CDS_LIB mstr_standard
J 0
(-5575 725);
PAINT MONO (-5575 725);
DISPLAY INVISIBLE (-5575 725);
FORCEPROP 1 LAST BODY_TYPE PLUMBING
J 0
(-5575 675);
DISPLAY 1.595745 (-5575 675);
PAINT GREEN (-5575 675);
DISPLAY INVISIBLE (-5575 675);
FORCEPROP 1 LAST HDL_TAP TRUE
J 0
(-5250 600);
DISPLAY 1.595745 (-5250 600);
PAINT GREEN (-5250 600);
DISPLAY INVISIBLE (-5250 600);
FORCEPROP 1 LAST PATH I8
J 0
(-5577 725);
DISPLAY 0.872340 (-5577 725);
PAINT GREEN (-5577 725);
DISPLAY INVISIBLE (-5577 725);
FORCEADD TAP..6
(-5575 4375);
FORCEPROP 3 LASTPIN (-5525 4375) SIG_NAME M_K_DQ<57>
J 0
(-5515 4385);
DISPLAY 0.659574 (-5515 4385);
PAINT MONO (-5515 4385);
DISPLAY INVISIBLE (-5515 4385);
FORCEPROP 1 LASTPIN (-5525 4375) BN 57
J 0
(-5577 4383);
DISPLAY 0.617021 (-5577 4383);
PAINT GREEN (-5577 4383);
FORCEPROP 2 LAST CDS_LIB mstr_standard
J 0
(-5575 4375);
PAINT MONO (-5575 4375);
DISPLAY INVISIBLE (-5575 4375);
FORCEPROP 1 LAST BODY_TYPE PLUMBING
J 0
(-5575 4325);
DISPLAY 1.595745 (-5575 4325);
PAINT GREEN (-5575 4325);
DISPLAY INVISIBLE (-5575 4325);
FORCEPROP 1 LAST HDL_TAP TRUE
J 0
(-5250 4250);
DISPLAY 1.595745 (-5250 4250);
PAINT GREEN (-5250 4250);
DISPLAY INVISIBLE (-5250 4250);
FORCEPROP 1 LAST PATH I80
J 0
(-5577 4375);
DISPLAY 0.872340 (-5577 4375);
PAINT GREEN (-5577 4375);
DISPLAY INVISIBLE (-5577 4375);
FORCEADD TAP..6
(-5575 4425);
FORCEPROP 3 LASTPIN (-5525 4425) SIG_NAME M_K_DQ<58>
J 0
(-5515 4435);
DISPLAY 0.659574 (-5515 4435);
PAINT MONO (-5515 4435);
DISPLAY INVISIBLE (-5515 4435);
FORCEPROP 1 LASTPIN (-5525 4425) BN 58
J 0
(-5577 4433);
DISPLAY 0.617021 (-5577 4433);
PAINT GREEN (-5577 4433);
FORCEPROP 2 LAST CDS_LIB mstr_standard
J 0
(-5575 4425);
PAINT MONO (-5575 4425);
DISPLAY INVISIBLE (-5575 4425);
FORCEPROP 1 LAST BODY_TYPE PLUMBING
J 0
(-5575 4375);
DISPLAY 1.595745 (-5575 4375);
PAINT GREEN (-5575 4375);
DISPLAY INVISIBLE (-5575 4375);
FORCEPROP 1 LAST HDL_TAP TRUE
J 0
(-5250 4300);
DISPLAY 1.595745 (-5250 4300);
PAINT GREEN (-5250 4300);
DISPLAY INVISIBLE (-5250 4300);
FORCEPROP 1 LAST PATH I81
J 0
(-5577 4425);
DISPLAY 0.872340 (-5577 4425);
PAINT GREEN (-5577 4425);
DISPLAY INVISIBLE (-5577 4425);
FORCEADD TAP..6
(-5575 4475);
FORCEPROP 3 LASTPIN (-5525 4475) SIG_NAME M_K_DQ<59>
J 0
(-5515 4485);
DISPLAY 0.659574 (-5515 4485);
PAINT MONO (-5515 4485);
DISPLAY INVISIBLE (-5515 4485);
FORCEPROP 1 LASTPIN (-5525 4475) BN 59
J 0
(-5577 4483);
DISPLAY 0.617021 (-5577 4483);
PAINT GREEN (-5577 4483);
FORCEPROP 2 LAST CDS_LIB mstr_standard
J 0
(-5575 4475);
PAINT MONO (-5575 4475);
DISPLAY INVISIBLE (-5575 4475);
FORCEPROP 1 LAST BODY_TYPE PLUMBING
J 0
(-5575 4425);
DISPLAY 1.595745 (-5575 4425);
PAINT GREEN (-5575 4425);
DISPLAY INVISIBLE (-5575 4425);
FORCEPROP 1 LAST HDL_TAP TRUE
J 0
(-5250 4350);
DISPLAY 1.595745 (-5250 4350);
PAINT GREEN (-5250 4350);
DISPLAY INVISIBLE (-5250 4350);
FORCEPROP 1 LAST PATH I82
J 0
(-5577 4475);
DISPLAY 0.872340 (-5577 4475);
PAINT GREEN (-5577 4475);
DISPLAY INVISIBLE (-5577 4475);
FORCEADD TAP..6
(-5575 4525);
FORCEPROP 3 LASTPIN (-5525 4525) SIG_NAME M_K_DQ<60>
J 0
(-5515 4535);
DISPLAY 0.659574 (-5515 4535);
PAINT MONO (-5515 4535);
DISPLAY INVISIBLE (-5515 4535);
FORCEPROP 1 LASTPIN (-5525 4525) BN 60
J 0
(-5577 4533);
DISPLAY 0.617021 (-5577 4533);
PAINT GREEN (-5577 4533);
FORCEPROP 2 LAST CDS_LIB mstr_standard
J 0
(-5575 4525);
PAINT MONO (-5575 4525);
DISPLAY INVISIBLE (-5575 4525);
FORCEPROP 1 LAST BODY_TYPE PLUMBING
J 0
(-5575 4475);
DISPLAY 1.595745 (-5575 4475);
PAINT GREEN (-5575 4475);
DISPLAY INVISIBLE (-5575 4475);
FORCEPROP 1 LAST HDL_TAP TRUE
J 0
(-5250 4400);
DISPLAY 1.595745 (-5250 4400);
PAINT GREEN (-5250 4400);
DISPLAY INVISIBLE (-5250 4400);
FORCEPROP 1 LAST PATH I83
J 0
(-5577 4525);
DISPLAY 0.872340 (-5577 4525);
PAINT GREEN (-5577 4525);
DISPLAY INVISIBLE (-5577 4525);
FORCEADD TAP..6
(-5575 4575);
FORCEPROP 3 LASTPIN (-5525 4575) SIG_NAME M_K_DQ<61>
J 0
(-5515 4585);
DISPLAY 0.659574 (-5515 4585);
PAINT MONO (-5515 4585);
DISPLAY INVISIBLE (-5515 4585);
FORCEPROP 1 LASTPIN (-5525 4575) BN 61
J 0
(-5577 4583);
DISPLAY 0.617021 (-5577 4583);
PAINT GREEN (-5577 4583);
FORCEPROP 2 LAST CDS_LIB mstr_standard
J 0
(-5575 4575);
PAINT MONO (-5575 4575);
DISPLAY INVISIBLE (-5575 4575);
FORCEPROP 1 LAST BODY_TYPE PLUMBING
J 0
(-5575 4525);
DISPLAY 1.595745 (-5575 4525);
PAINT GREEN (-5575 4525);
DISPLAY INVISIBLE (-5575 4525);
FORCEPROP 1 LAST HDL_TAP TRUE
J 0
(-5250 4450);
DISPLAY 1.595745 (-5250 4450);
PAINT GREEN (-5250 4450);
DISPLAY INVISIBLE (-5250 4450);
FORCEPROP 1 LAST PATH I84
J 0
(-5577 4575);
DISPLAY 0.872340 (-5577 4575);
PAINT GREEN (-5577 4575);
DISPLAY INVISIBLE (-5577 4575);
FORCEADD TAP..6
(-5575 4625);
FORCEPROP 3 LASTPIN (-5525 4625) SIG_NAME M_K_DQ<62>
J 0
(-5515 4635);
DISPLAY 0.659574 (-5515 4635);
PAINT MONO (-5515 4635);
DISPLAY INVISIBLE (-5515 4635);
FORCEPROP 1 LASTPIN (-5525 4625) BN 62
J 0
(-5577 4633);
DISPLAY 0.617021 (-5577 4633);
PAINT GREEN (-5577 4633);
FORCEPROP 2 LAST CDS_LIB mstr_standard
J 0
(-5575 4625);
PAINT MONO (-5575 4625);
DISPLAY INVISIBLE (-5575 4625);
FORCEPROP 1 LAST BODY_TYPE PLUMBING
J 0
(-5575 4575);
DISPLAY 1.595745 (-5575 4575);
PAINT GREEN (-5575 4575);
DISPLAY INVISIBLE (-5575 4575);
FORCEPROP 1 LAST HDL_TAP TRUE
J 0
(-5250 4500);
DISPLAY 1.595745 (-5250 4500);
PAINT GREEN (-5250 4500);
DISPLAY INVISIBLE (-5250 4500);
FORCEPROP 1 LAST PATH I85
J 0
(-5577 4625);
DISPLAY 0.872340 (-5577 4625);
PAINT GREEN (-5577 4625);
DISPLAY INVISIBLE (-5577 4625);
FORCEADD TAP..6
(-5575 4675);
FORCEPROP 3 LASTPIN (-5525 4675) SIG_NAME M_K_DQ<63>
J 0
(-5515 4685);
DISPLAY 0.659574 (-5515 4685);
PAINT MONO (-5515 4685);
DISPLAY INVISIBLE (-5515 4685);
FORCEPROP 1 LASTPIN (-5525 4675) BN 63
J 0
(-5577 4683);
DISPLAY 0.617021 (-5577 4683);
PAINT GREEN (-5577 4683);
FORCEPROP 2 LAST CDS_LIB mstr_standard
J 0
(-5575 4675);
PAINT MONO (-5575 4675);
DISPLAY INVISIBLE (-5575 4675);
FORCEPROP 1 LAST BODY_TYPE PLUMBING
J 0
(-5575 4625);
DISPLAY 1.595745 (-5575 4625);
PAINT GREEN (-5575 4625);
DISPLAY INVISIBLE (-5575 4625);
FORCEPROP 1 LAST HDL_TAP TRUE
J 0
(-5250 4550);
DISPLAY 1.595745 (-5250 4550);
PAINT GREEN (-5250 4550);
DISPLAY INVISIBLE (-5250 4550);
FORCEPROP 1 LAST PATH I86
J 0
(-5577 4675);
DISPLAY 0.872340 (-5577 4675);
PAINT GREEN (-5577 4675);
DISPLAY INVISIBLE (-5577 4675);
FORCEADD TAP..6
R 2
(-2850 775);
FORCEPROP 3 LASTPIN (-2900 775) SIG_NAME M_K_BA<1>
J 0
(-2890 785);
DISPLAY 0.659574 (-2890 785);
PAINT MONO (-2890 785);
DISPLAY INVISIBLE (-2890 785);
FORCEPROP 1 LASTPIN (-2900 775) BN 1
J 2
(-2848 783);
DISPLAY 0.617021 (-2848 783);
PAINT GREEN (-2848 783);
FORCEPROP 2 LAST CDS_LIB mstr_standard
J 0
(-2850 775);
PAINT MONO (-2850 775);
DISPLAY INVISIBLE (-2850 775);
FORCEPROP 1 LAST BODY_TYPE PLUMBING
J 2
(-2850 725);
DISPLAY 1.595745 (-2850 725);
PAINT GREEN (-2850 725);
DISPLAY INVISIBLE (-2850 725);
FORCEPROP 1 LAST HDL_TAP TRUE
J 2
(-3175 650);
DISPLAY 1.595745 (-3175 650);
PAINT GREEN (-3175 650);
DISPLAY INVISIBLE (-3175 650);
FORCEPROP 1 LAST PATH I87
J 2
(-2848 775);
DISPLAY 0.872340 (-2848 775);
PAINT GREEN (-2848 775);
DISPLAY INVISIBLE (-2848 775);
FORCEADD TAP..6
R 2
(-2850 725);
FORCEPROP 3 LASTPIN (-2900 725) SIG_NAME M_K_BA<0>
J 0
(-2890 735);
DISPLAY 0.659574 (-2890 735);
PAINT MONO (-2890 735);
DISPLAY INVISIBLE (-2890 735);
FORCEPROP 1 LASTPIN (-2900 725) BN 0
J 2
(-2848 733);
DISPLAY 0.617021 (-2848 733);
PAINT GREEN (-2848 733);
FORCEPROP 2 LAST CDS_LIB mstr_standard
J 0
(-2850 725);
PAINT MONO (-2850 725);
DISPLAY INVISIBLE (-2850 725);
FORCEPROP 1 LAST BODY_TYPE PLUMBING
J 2
(-2850 675);
DISPLAY 1.595745 (-2850 675);
PAINT GREEN (-2850 675);
DISPLAY INVISIBLE (-2850 675);
FORCEPROP 1 LAST HDL_TAP TRUE
J 2
(-3175 600);
DISPLAY 1.595745 (-3175 600);
PAINT GREEN (-3175 600);
DISPLAY INVISIBLE (-3175 600);
FORCEPROP 1 LAST PATH I88
J 2
(-2848 725);
DISPLAY 0.872340 (-2848 725);
PAINT GREEN (-2848 725);
DISPLAY INVISIBLE (-2848 725);
FORCEADD TAP..6
R 2
(-2850 825);
FORCEPROP 3 LASTPIN (-2900 825) SIG_NAME M_K_BG<0>
J 0
(-2890 835);
DISPLAY 0.659574 (-2890 835);
PAINT MONO (-2890 835);
DISPLAY INVISIBLE (-2890 835);
FORCEPROP 1 LASTPIN (-2900 825) BN 0
J 2
(-2848 833);
DISPLAY 0.617021 (-2848 833);
PAINT GREEN (-2848 833);
FORCEPROP 2 LAST CDS_LIB mstr_standard
J 0
(-2850 825);
PAINT MONO (-2850 825);
DISPLAY INVISIBLE (-2850 825);
FORCEPROP 1 LAST BODY_TYPE PLUMBING
J 2
(-2850 775);
DISPLAY 1.595745 (-2850 775);
PAINT GREEN (-2850 775);
DISPLAY INVISIBLE (-2850 775);
FORCEPROP 1 LAST HDL_TAP TRUE
J 2
(-3175 700);
DISPLAY 1.595745 (-3175 700);
PAINT GREEN (-3175 700);
DISPLAY INVISIBLE (-3175 700);
FORCEPROP 1 LAST PATH I89
J 2
(-2848 825);
DISPLAY 0.872340 (-2848 825);
PAINT GREEN (-2848 825);
DISPLAY INVISIBLE (-2848 825);
FORCEADD TAP..6
(-5575 875);
FORCEPROP 3 LASTPIN (-5525 875) SIG_NAME M_K_CLK_DP<1>
J 0
(-5515 885);
DISPLAY 0.659574 (-5515 885);
PAINT MONO (-5515 885);
DISPLAY INVISIBLE (-5515 885);
FORCEPROP 1 LASTPIN (-5525 875) BN 1
J 0
(-5577 883);
DISPLAY 0.617021 (-5577 883);
PAINT GREEN (-5577 883);
FORCEPROP 2 LAST CDS_LIB mstr_standard
J 0
(-5575 875);
PAINT MONO (-5575 875);
DISPLAY INVISIBLE (-5575 875);
FORCEPROP 1 LAST BODY_TYPE PLUMBING
J 0
(-5575 825);
DISPLAY 1.595745 (-5575 825);
PAINT GREEN (-5575 825);
DISPLAY INVISIBLE (-5575 825);
FORCEPROP 1 LAST HDL_TAP TRUE
J 0
(-5250 750);
DISPLAY 1.595745 (-5250 750);
PAINT GREEN (-5250 750);
DISPLAY INVISIBLE (-5250 750);
FORCEPROP 1 LAST PATH I9
J 0
(-5577 875);
DISPLAY 0.872340 (-5577 875);
PAINT GREEN (-5577 875);
DISPLAY INVISIBLE (-5577 875);
FORCEADD TAP..6
R 2
(-2850 875);
FORCEPROP 3 LASTPIN (-2900 875) SIG_NAME M_K_BG<1>
J 0
(-2890 885);
DISPLAY 0.659574 (-2890 885);
PAINT MONO (-2890 885);
DISPLAY INVISIBLE (-2890 885);
FORCEPROP 1 LASTPIN (-2900 875) BN 1
J 2
(-2848 883);
DISPLAY 0.617021 (-2848 883);
PAINT GREEN (-2848 883);
FORCEPROP 2 LAST CDS_LIB mstr_standard
J 0
(-2850 875);
PAINT MONO (-2850 875);
DISPLAY INVISIBLE (-2850 875);
FORCEPROP 1 LAST BODY_TYPE PLUMBING
J 2
(-2850 825);
DISPLAY 1.595745 (-2850 825);
PAINT GREEN (-2850 825);
DISPLAY INVISIBLE (-2850 825);
FORCEPROP 1 LAST HDL_TAP TRUE
J 2
(-3175 750);
DISPLAY 1.595745 (-3175 750);
PAINT GREEN (-3175 750);
DISPLAY INVISIBLE (-3175 750);
FORCEPROP 1 LAST PATH I90
J 2
(-2848 875);
DISPLAY 0.872340 (-2848 875);
PAINT GREEN (-2848 875);
DISPLAY INVISIBLE (-2848 875);
FORCEADD TAP..6
R 2
(-2850 1075);
FORCEPROP 3 LASTPIN (-2900 1075) SIG_NAME M_K_CS_N<2>
J 0
(-2890 1085);
DISPLAY 0.659574 (-2890 1085);
PAINT MONO (-2890 1085);
DISPLAY INVISIBLE (-2890 1085);
FORCEPROP 1 LASTPIN (-2900 1075) BN 2
J 2
(-2848 1083);
DISPLAY 0.617021 (-2848 1083);
PAINT GREEN (-2848 1083);
FORCEPROP 2 LAST CDS_LIB mstr_standard
J 0
(-2850 1075);
PAINT MONO (-2850 1075);
DISPLAY INVISIBLE (-2850 1075);
FORCEPROP 1 LAST BODY_TYPE PLUMBING
J 2
(-2850 1025);
DISPLAY 1.595745 (-2850 1025);
PAINT GREEN (-2850 1025);
DISPLAY INVISIBLE (-2850 1025);
FORCEPROP 1 LAST HDL_TAP TRUE
J 2
(-3175 950);
DISPLAY 1.595745 (-3175 950);
PAINT GREEN (-3175 950);
DISPLAY INVISIBLE (-3175 950);
FORCEPROP 1 LAST PATH I91
J 2
(-2848 1075);
DISPLAY 0.872340 (-2848 1075);
PAINT GREEN (-2848 1075);
DISPLAY INVISIBLE (-2848 1075);
FORCEADD TAP..6
R 2
(-2850 1025);
FORCEPROP 3 LASTPIN (-2900 1025) SIG_NAME M_K_CS_N<1>
J 0
(-2890 1035);
DISPLAY 0.659574 (-2890 1035);
PAINT MONO (-2890 1035);
DISPLAY INVISIBLE (-2890 1035);
FORCEPROP 1 LASTPIN (-2900 1025) BN 1
J 2
(-2848 1033);
DISPLAY 0.617021 (-2848 1033);
PAINT GREEN (-2848 1033);
FORCEPROP 2 LAST CDS_LIB mstr_standard
J 0
(-2850 1025);
PAINT MONO (-2850 1025);
DISPLAY INVISIBLE (-2850 1025);
FORCEPROP 1 LAST BODY_TYPE PLUMBING
J 2
(-2850 975);
DISPLAY 1.595745 (-2850 975);
PAINT GREEN (-2850 975);
DISPLAY INVISIBLE (-2850 975);
FORCEPROP 1 LAST HDL_TAP TRUE
J 2
(-3175 900);
DISPLAY 1.595745 (-3175 900);
PAINT GREEN (-3175 900);
DISPLAY INVISIBLE (-3175 900);
FORCEPROP 1 LAST PATH I92
J 2
(-2848 1025);
DISPLAY 0.872340 (-2848 1025);
PAINT GREEN (-2848 1025);
DISPLAY INVISIBLE (-2848 1025);
FORCEADD TAP..6
R 2
(-2850 975);
FORCEPROP 3 LASTPIN (-2900 975) SIG_NAME M_K_CS_N<0>
J 0
(-2890 985);
DISPLAY 0.659574 (-2890 985);
PAINT MONO (-2890 985);
DISPLAY INVISIBLE (-2890 985);
FORCEPROP 1 LASTPIN (-2900 975) BN 0
J 2
(-2848 983);
DISPLAY 0.617021 (-2848 983);
PAINT GREEN (-2848 983);
FORCEPROP 2 LAST CDS_LIB mstr_standard
J 0
(-2850 975);
PAINT MONO (-2850 975);
DISPLAY INVISIBLE (-2850 975);
FORCEPROP 1 LAST BODY_TYPE PLUMBING
J 2
(-2850 925);
DISPLAY 1.595745 (-2850 925);
PAINT GREEN (-2850 925);
DISPLAY INVISIBLE (-2850 925);
FORCEPROP 1 LAST HDL_TAP TRUE
J 2
(-3175 850);
DISPLAY 1.595745 (-3175 850);
PAINT GREEN (-3175 850);
DISPLAY INVISIBLE (-3175 850);
FORCEPROP 1 LAST PATH I93
J 2
(-2848 975);
DISPLAY 0.872340 (-2848 975);
PAINT GREEN (-2848 975);
DISPLAY INVISIBLE (-2848 975);
FORCEADD TAP..6
R 2
(-2850 1175);
FORCEPROP 3 LASTPIN (-2900 1175) SIG_NAME M_K_CS_N<4>
J 0
(-2890 1185);
DISPLAY 0.659574 (-2890 1185);
PAINT MONO (-2890 1185);
DISPLAY INVISIBLE (-2890 1185);
FORCEPROP 1 LASTPIN (-2900 1175) BN 4
J 2
(-2848 1183);
DISPLAY 0.617021 (-2848 1183);
PAINT GREEN (-2848 1183);
FORCEPROP 2 LAST CDS_LIB mstr_standard
J 0
(-2850 1175);
PAINT MONO (-2850 1175);
DISPLAY INVISIBLE (-2850 1175);
FORCEPROP 1 LAST BODY_TYPE PLUMBING
J 2
(-2850 1125);
DISPLAY 1.595745 (-2850 1125);
PAINT GREEN (-2850 1125);
DISPLAY INVISIBLE (-2850 1125);
FORCEPROP 1 LAST HDL_TAP TRUE
J 2
(-3175 1050);
DISPLAY 1.595745 (-3175 1050);
PAINT GREEN (-3175 1050);
DISPLAY INVISIBLE (-3175 1050);
FORCEPROP 1 LAST PATH I94
J 2
(-2848 1175);
DISPLAY 0.872340 (-2848 1175);
PAINT GREEN (-2848 1175);
DISPLAY INVISIBLE (-2848 1175);
FORCEADD TAP..6
R 2
(-2850 1125);
FORCEPROP 3 LASTPIN (-2900 1125) SIG_NAME M_K_CS_N<3>
J 0
(-2890 1135);
DISPLAY 0.659574 (-2890 1135);
PAINT MONO (-2890 1135);
DISPLAY INVISIBLE (-2890 1135);
FORCEPROP 1 LASTPIN (-2900 1125) BN 3
J 2
(-2848 1133);
DISPLAY 0.617021 (-2848 1133);
PAINT GREEN (-2848 1133);
FORCEPROP 2 LAST CDS_LIB mstr_standard
J 0
(-2850 1125);
PAINT MONO (-2850 1125);
DISPLAY INVISIBLE (-2850 1125);
FORCEPROP 1 LAST BODY_TYPE PLUMBING
J 2
(-2850 1075);
DISPLAY 1.595745 (-2850 1075);
PAINT GREEN (-2850 1075);
DISPLAY INVISIBLE (-2850 1075);
FORCEPROP 1 LAST HDL_TAP TRUE
J 2
(-3175 1000);
DISPLAY 1.595745 (-3175 1000);
PAINT GREEN (-3175 1000);
DISPLAY INVISIBLE (-3175 1000);
FORCEPROP 1 LAST PATH I95
J 2
(-2848 1125);
DISPLAY 0.872340 (-2848 1125);
PAINT GREEN (-2848 1125);
DISPLAY INVISIBLE (-2848 1125);
FORCEADD TAP..6
R 2
(-2850 1225);
FORCEPROP 3 LASTPIN (-2900 1225) SIG_NAME M_K_CS_N<5>
J 0
(-2890 1235);
DISPLAY 0.659574 (-2890 1235);
PAINT MONO (-2890 1235);
DISPLAY INVISIBLE (-2890 1235);
FORCEPROP 1 LASTPIN (-2900 1225) BN 5
J 2
(-2848 1233);
DISPLAY 0.617021 (-2848 1233);
PAINT GREEN (-2848 1233);
FORCEPROP 2 LAST CDS_LIB mstr_standard
J 0
(-2850 1225);
PAINT MONO (-2850 1225);
DISPLAY INVISIBLE (-2850 1225);
FORCEPROP 1 LAST BODY_TYPE PLUMBING
J 2
(-2850 1175);
DISPLAY 1.595745 (-2850 1175);
PAINT GREEN (-2850 1175);
DISPLAY INVISIBLE (-2850 1175);
FORCEPROP 1 LAST HDL_TAP TRUE
J 2
(-3175 1100);
DISPLAY 1.595745 (-3175 1100);
PAINT GREEN (-3175 1100);
DISPLAY INVISIBLE (-3175 1100);
FORCEPROP 1 LAST PATH I96
J 2
(-2848 1225);
DISPLAY 0.872340 (-2848 1225);
PAINT GREEN (-2848 1225);
DISPLAY INVISIBLE (-2848 1225);
FORCEADD TAP..6
R 2
(-2850 1275);
FORCEPROP 3 LASTPIN (-2900 1275) SIG_NAME M_K_CS_N<6>
J 0
(-2890 1285);
DISPLAY 0.659574 (-2890 1285);
PAINT MONO (-2890 1285);
DISPLAY INVISIBLE (-2890 1285);
FORCEPROP 1 LASTPIN (-2900 1275) BN 6
J 2
(-2848 1283);
DISPLAY 0.617021 (-2848 1283);
PAINT GREEN (-2848 1283);
FORCEPROP 2 LAST CDS_LIB mstr_standard
J 0
(-2850 1275);
PAINT MONO (-2850 1275);
DISPLAY INVISIBLE (-2850 1275);
FORCEPROP 1 LAST BODY_TYPE PLUMBING
J 2
(-2850 1225);
DISPLAY 1.595745 (-2850 1225);
PAINT GREEN (-2850 1225);
DISPLAY INVISIBLE (-2850 1225);
FORCEPROP 1 LAST HDL_TAP TRUE
J 2
(-3175 1150);
DISPLAY 1.595745 (-3175 1150);
PAINT GREEN (-3175 1150);
DISPLAY INVISIBLE (-3175 1150);
FORCEPROP 1 LAST PATH I97
J 2
(-2848 1275);
DISPLAY 0.872340 (-2848 1275);
PAINT GREEN (-2848 1275);
DISPLAY INVISIBLE (-2848 1275);
FORCEADD TAP..6
R 2
(-2850 1325);
FORCEPROP 3 LASTPIN (-2900 1325) SIG_NAME M_K_CS_N<7>
J 0
(-2890 1335);
DISPLAY 0.659574 (-2890 1335);
PAINT MONO (-2890 1335);
DISPLAY INVISIBLE (-2890 1335);
FORCEPROP 1 LASTPIN (-2900 1325) BN 7
J 2
(-2848 1333);
DISPLAY 0.617021 (-2848 1333);
PAINT GREEN (-2848 1333);
FORCEPROP 2 LAST CDS_LIB mstr_standard
J 0
(-2850 1325);
PAINT MONO (-2850 1325);
DISPLAY INVISIBLE (-2850 1325);
FORCEPROP 1 LAST BODY_TYPE PLUMBING
J 2
(-2850 1275);
DISPLAY 1.595745 (-2850 1275);
PAINT GREEN (-2850 1275);
DISPLAY INVISIBLE (-2850 1275);
FORCEPROP 1 LAST HDL_TAP TRUE
J 2
(-3175 1200);
DISPLAY 1.595745 (-3175 1200);
PAINT GREEN (-3175 1200);
DISPLAY INVISIBLE (-3175 1200);
FORCEPROP 1 LAST PATH I98
J 2
(-2848 1325);
DISPLAY 0.872340 (-2848 1325);
PAINT GREEN (-2848 1325);
DISPLAY INVISIBLE (-2848 1325);
FORCEADD TAP..6
R 2
(-2850 1425);
FORCEPROP 3 LASTPIN (-2900 1425) SIG_NAME M_K_ODT<0>
J 0
(-2890 1435);
DISPLAY 0.659574 (-2890 1435);
PAINT MONO (-2890 1435);
DISPLAY INVISIBLE (-2890 1435);
FORCEPROP 1 LASTPIN (-2900 1425) BN 0
J 2
(-2848 1433);
DISPLAY 0.617021 (-2848 1433);
PAINT GREEN (-2848 1433);
FORCEPROP 2 LAST CDS_LIB mstr_standard
J 0
(-2850 1425);
PAINT MONO (-2850 1425);
DISPLAY INVISIBLE (-2850 1425);
FORCEPROP 1 LAST BODY_TYPE PLUMBING
J 2
(-2850 1375);
DISPLAY 1.595745 (-2850 1375);
PAINT GREEN (-2850 1375);
DISPLAY INVISIBLE (-2850 1375);
FORCEPROP 1 LAST HDL_TAP TRUE
J 2
(-3175 1300);
DISPLAY 1.595745 (-3175 1300);
PAINT GREEN (-3175 1300);
DISPLAY INVISIBLE (-3175 1300);
FORCEPROP 1 LAST PATH I99
J 2
(-2848 1425);
DISPLAY 0.872340 (-2848 1425);
PAINT GREEN (-2848 1425);
DISPLAY INVISIBLE (-2848 1425);
FORCEADD DESIGN_NOTE..1
(-6325 375);
FORCEPROP 0 LAST L1 CPU SYMBOLS 1-30 ARE PRELIMINARY AND SUBJECT TO CHANGE
J 0
(-6525 250);
DISPLAY 1.021277 (-6525 250);
PAINT ORANGE (-6525 250);
FORCEPROP 2 LAST CDS_LIB mstr_symbols
J 0
(-6325 375);
PAINT ORANGE (-6325 375);
DISPLAY INVISIBLE (-6325 375);
FORCEPROP 1 LAST COMMENT_BODY TRUE
J 0
(-6300 475);
DISPLAY 0.978723 (-6300 475);
PAINT ORANGE (-6300 475);
DISPLAY INVISIBLE (-6300 475);
FORCEADD PRELIM..10
(-4215 2565);
PAINT GRAY (-4215 2565);
FORCEPROP 2 LAST CDS_LIB mstr_misc
J 0
(-4215 2565);
PAINT ORANGE (-4215 2565);
DISPLAY INVISIBLE (-4215 2565);
FORCEPROP 1 LAST COMMENT_BODY TRUE
J 0
(-4215 2565);
PAINT ORANGE (-4215 2565);
DISPLAY INVISIBLE (-4215 2565);
FORCEADD INTEL_CORP_BPAGE..1
(0 0);
FORCEPROP 1 LAST CDS_CON_LAST_MODIFIED Tue Dec 01 11:51:35 2015
J 0
(-1425 325);
DISPLAY 1.340426 (-1425 325);
PAINT GREEN (-1425 325);
DISPLAY INVISIBLE (-1425 325);
FORCEPROP 1 LAST CUSTOM_TXT_CDS <CURRENT_DESIGN_SHEET> OF <TOTAL_DESIGN_SHEETS>
J 0
(-500 25);
PAINT GREEN (-500 25);
FORCEPROP 1 LAST CUSTOM_TXT_CDS <CON_LAST_MODIFIED>
J 0
(-1925 350);
PAINT GREEN (-1925 350);
FORCEPROP 2 LAST CUSTOM_TXT_CDS <XR_PAGE_TITLE>
J 0
(-7890 5250);
DISPLAY 0.638298 (-7890 5250);
PAINT PINK (-7890 5250);
DISPLAY INVISIBLE (-7890 5250);
FORCEPROP 1 LAST SCH_ADDRESS3 Santa Clara, CA 95052-8119
J 0
(-3975 25);
DISPLAY 0.617021 (-3975 25);
PAINT GREEN (-3975 25);
FORCEPROP 1 LAST SCH_ADDRESS2 P.O. BOX 58119
J 0
(-3975 75);
DISPLAY 0.617021 (-3975 75);
PAINT GREEN (-3975 75);
FORCEPROP 1 LAST SCH_ADDRESS1 2200 Mission College Blvd.
J 0
(-3975 125);
DISPLAY 0.617021 (-3975 125);
PAINT GREEN (-3975 125);
FORCEPROP 1 LAST SCH_TITLE SKYLAKE - SKT1 - 6 OF 21
J 0
(-7950 50);
DISPLAY 1.212766 (-7950 50);
PAINT GREEN (-7950 50);
FORCEPROP 1 LAST SCH_NUMBER H4694802
J 0
(-1300 150);
DISPLAY 1.212766 (-1300 150);
PAINT YELLOW (-1300 150);
FORCEPROP 1 LAST SCH_DEPT BESD
J 1
(-4450 100);
DISPLAY 1.212766 (-4450 100);
PAINT YELLOW (-4450 100);
FORCEPROP 1 LAST SCH_REV 2.420
J 0
(-250 150);
DISPLAY 0.978723 (-250 150);
PAINT YELLOW (-250 150);
FORCEPROP 2 LAST PAGE_BORDER TRUE
J 0
(-7890 5250);
DISPLAY 0.851064 (-7890 5250);
PAINT PINK (-7890 5250);
DISPLAY INVISIBLE (-7890 5250);
FORCEPROP 2 LAST CDS_LIB mstr_symbols
J 0
(0 0);
PAINT ORANGE (0 0);
DISPLAY INVISIBLE (0 0);
FORCEPROP 1 LAST COMMENT_BODY TRUE
J 0
(12 12);
DISPLAY 0.638298 (12 12);
PAINT GREEN (12 12);
DISPLAY INVISIBLE (12 12);
FORCEPROP 2 LAST CDS_XR_PAGE_TITLE CR-60 : @BASEBOARD_FAB2_LIB.BASEBOARD_FAB2(SCH_1):PAGE60
J 0
(-7890 5250);
DISPLAY 0.638298 (-7890 5250);
PAINT PINK (-7890 5250);
DISPLAY INVISIBLE (-7890 5250);
WIRE 17 -1 (-2800 4700)(-2800 4750);
WIRE 17 -1 (-2800 4650)(-2800 4700);
WIRE 17 -1 (-2050 4750)(-2800 4750);
FORCEPROP 2 LAST SIG_NAME M_K_DQS_DP<17:0>
J 0
(-2700 4760);
DISPLAY 0.617021 (-2700 4760);
PAINT ORANGE (-2700 4760);
WIRE 17 -1 (-2800 4600)(-2800 4650);
WIRE 17 -1 (-2800 4550)(-2800 4600);
WIRE 17 -1 (-2800 4500)(-2800 4550);
WIRE 17 -1 (-2800 4450)(-2800 4500);
WIRE 17 -1 (-2800 4400)(-2800 4450);
WIRE 17 -1 (-2800 4350)(-2800 4400);
WIRE 17 -1 (-2800 4300)(-2800 4350);
WIRE 17 -1 (-2800 4250)(-2800 4300);
WIRE 17 -1 (-2800 4200)(-2800 4250);
WIRE 17 -1 (-2800 4150)(-2800 4200);
WIRE 17 -1 (-2800 4100)(-2800 4150);
WIRE 17 -1 (-2800 4050)(-2800 4100);
WIRE 17 -1 (-2800 4000)(-2800 4050);
WIRE 17 -1 (-2800 3950)(-2800 4000);
WIRE 17 -1 (-2800 3900)(-2800 3950);
WIRE 17 -1 (-2800 3850)(-2800 3900);
WIRE 17 -1 (-2800 3750)(-2800 3775);
WIRE 17 -1 (-2800 3700)(-2800 3750);
WIRE 17 -1 (-2050 3775)(-2800 3775);
FORCEPROP 2 LAST SIG_NAME M_K_DQS_DN<17:0>
J 0
(-2700 3785);
DISPLAY 0.617021 (-2700 3785);
PAINT ORANGE (-2700 3785);
WIRE 17 -1 (-2800 3650)(-2800 3700);
WIRE 17 -1 (-2800 3600)(-2800 3650);
WIRE 17 -1 (-2800 3550)(-2800 3600);
WIRE 17 -1 (-2800 3500)(-2800 3550);
WIRE 17 -1 (-2800 3450)(-2800 3500);
WIRE 17 -1 (-2800 3400)(-2800 3450);
WIRE 17 -1 (-2800 3350)(-2800 3400);
WIRE 17 -1 (-2800 3300)(-2800 3350);
WIRE 17 -1 (-2800 3250)(-2800 3300);
WIRE 17 -1 (-2800 3200)(-2800 3250);
WIRE 17 -1 (-2800 3150)(-2800 3200);
WIRE 17 -1 (-2800 3100)(-2800 3150);
WIRE 17 -1 (-2800 3050)(-2800 3100);
WIRE 17 -1 (-2800 3000)(-2800 3050);
WIRE 17 -1 (-2800 2950)(-2800 3000);
WIRE 17 -1 (-2800 2900)(-2800 2950);
WIRE 17 -1 (-2800 2800)(-2800 2825);
WIRE 17 -1 (-2800 2750)(-2800 2800);
WIRE 17 -1 (-2050 2825)(-2800 2825);
FORCEPROP 2 LAST SIG_NAME M_K_MA<17:0>
J 0
(-2700 2835);
DISPLAY 0.617021 (-2700 2835);
PAINT ORANGE (-2700 2835);
WIRE 17 -1 (-2800 2700)(-2800 2750);
WIRE 17 -1 (-2800 2650)(-2800 2700);
WIRE 17 -1 (-2800 2600)(-2800 2650);
WIRE 17 -1 (-2800 2550)(-2800 2600);
WIRE 17 -1 (-2800 2500)(-2800 2550);
WIRE 17 -1 (-2800 2450)(-2800 2500);
WIRE 17 -1 (-2800 2400)(-2800 2450);
WIRE 17 -1 (-2800 2350)(-2800 2400);
WIRE 17 -1 (-2800 2300)(-2800 2350);
WIRE 17 -1 (-2800 2250)(-2800 2300);
WIRE 17 -1 (-2800 2200)(-2800 2250);
WIRE 17 -1 (-2800 2150)(-2800 2200);
WIRE 17 -1 (-2800 2100)(-2800 2150);
WIRE 17 -1 (-2800 2050)(-2800 2100);
WIRE 17 -1 (-2800 2000)(-2800 2050);
WIRE 17 -1 (-2800 1950)(-2800 2000);
WIRE 17 -1 (-2800 800)(-2800 825);
WIRE 17 -1 (-2800 750)(-2800 800);
WIRE 17 -1 (-2050 825)(-2800 825);
FORCEPROP 2 LAST SIG_NAME M_K_BA<1:0>
J 0
(-2700 835);
DISPLAY 0.617021 (-2700 835);
PAINT ORANGE (-2700 835);
WIRE 17 -1 (-2800 850)(-2800 900);
WIRE 17 -1 (-2800 900)(-2800 925);
WIRE 17 -1 (-2050 925)(-2800 925);
FORCEPROP 2 LAST SIG_NAME M_K_BG<1:0>
J 0
(-2700 935);
DISPLAY 0.617021 (-2700 935);
PAINT ORANGE (-2700 935);
WIRE 17 -1 (-2800 1850)(-2800 1875);
WIRE 17 -1 (-2800 1800)(-2800 1850);
WIRE 17 -1 (-2050 1875)(-2800 1875);
FORCEPROP 2 LAST SIG_NAME M_K_CKE<3:0>
J 0
(-2700 1885);
DISPLAY 0.617021 (-2700 1885);
PAINT ORANGE (-2700 1885);
WIRE 17 -1 (-2800 1750)(-2800 1800);
WIRE 17 -1 (-2800 1700)(-2800 1750);
WIRE 17 -1 (-2800 1350)(-2800 1375);
WIRE 17 -1 (-2800 1300)(-2800 1350);
WIRE 17 -1 (-2050 1375)(-2800 1375);
FORCEPROP 2 LAST SIG_NAME M_K_CS_N<7:0>
J 0
(-2700 1385);
DISPLAY 0.617021 (-2700 1385);
PAINT ORANGE (-2700 1385);
WIRE 17 -1 (-2800 1250)(-2800 1300);
WIRE 17 -1 (-2800 1200)(-2800 1250);
WIRE 17 -1 (-2800 1150)(-2800 1200);
WIRE 17 -1 (-2800 1100)(-2800 1150);
WIRE 17 -1 (-2800 1050)(-2800 1100);
WIRE 17 -1 (-2800 1000)(-2800 1050);
WIRE 17 -1 (-2800 1600)(-2800 1625);
WIRE 17 -1 (-2800 1550)(-2800 1600);
WIRE 17 -1 (-2050 1625)(-2800 1625);
FORCEPROP 2 LAST SIG_NAME M_K_ODT<3:0>
J 0
(-2700 1635);
DISPLAY 0.617021 (-2700 1635);
PAINT ORANGE (-2700 1635);
WIRE 17 -1 (-2800 1500)(-2800 1550);
WIRE 17 -1 (-2800 1450)(-2800 1500);
WIRE 17 -1 (-5625 4700)(-5625 4800);
WIRE 17 -1 (-5625 4650)(-5625 4700);
WIRE 17 -1 (-5625 4800)(-6375 4800);
FORCEPROP 2 LAST SIG_NAME M_K_DQ<63:0>
J 0
(-6325 4810);
DISPLAY 0.617021 (-6325 4810);
PAINT ORANGE (-6325 4810);
WIRE 17 -1 (-5625 4600)(-5625 4650);
WIRE 17 -1 (-5625 4550)(-5625 4600);
WIRE 17 -1 (-5625 4500)(-5625 4550);
WIRE 17 -1 (-5625 4450)(-5625 4500);
WIRE 17 -1 (-5625 4400)(-5625 4450);
WIRE 17 -1 (-5625 4350)(-5625 4400);
WIRE 17 -1 (-5625 4300)(-5625 4350);
WIRE 17 -1 (-5625 4250)(-5625 4300);
WIRE 17 -1 (-5625 4200)(-5625 4250);
WIRE 17 -1 (-5625 4150)(-5625 4200);
WIRE 17 -1 (-5625 4100)(-5625 4150);
WIRE 17 -1 (-5625 4050)(-5625 4100);
WIRE 17 -1 (-5625 4000)(-5625 4050);
WIRE 17 -1 (-5625 3950)(-5625 4000);
WIRE 17 -1 (-5625 3900)(-5625 3950);
WIRE 17 -1 (-5625 3850)(-5625 3900);
WIRE 17 -1 (-5625 3800)(-5625 3850);
WIRE 17 -1 (-5625 3750)(-5625 3800);
WIRE 17 -1 (-5625 3700)(-5625 3750);
WIRE 17 -1 (-5625 3650)(-5625 3700);
WIRE 17 -1 (-5625 3600)(-5625 3650);
WIRE 17 -1 (-5625 3550)(-5625 3600);
WIRE 17 -1 (-5625 3500)(-5625 3550);
WIRE 17 -1 (-5625 3450)(-5625 3500);
WIRE 17 -1 (-5625 3400)(-5625 3450);
WIRE 17 -1 (-5625 3350)(-5625 3400);
WIRE 17 -1 (-5625 3300)(-5625 3350);
WIRE 17 -1 (-5625 3250)(-5625 3300);
WIRE 17 -1 (-5625 3200)(-5625 3250);
WIRE 17 -1 (-5625 3150)(-5625 3200);
WIRE 17 -1 (-5625 3100)(-5625 3150);
WIRE 17 -1 (-5625 3050)(-5625 3100);
WIRE 17 -1 (-5625 3000)(-5625 3050);
WIRE 17 -1 (-5625 2950)(-5625 3000);
WIRE 17 -1 (-5625 2900)(-5625 2950);
WIRE 17 -1 (-5625 2850)(-5625 2900);
WIRE 17 -1 (-5625 2800)(-5625 2850);
WIRE 17 -1 (-5625 2750)(-5625 2800);
WIRE 17 -1 (-5625 2700)(-5625 2750);
WIRE 17 -1 (-5625 2650)(-5625 2700);
WIRE 17 -1 (-5625 2600)(-5625 2650);
WIRE 17 -1 (-5625 2550)(-5625 2600);
WIRE 17 -1 (-5625 2500)(-5625 2550);
WIRE 17 -1 (-5625 2450)(-5625 2500);
WIRE 17 -1 (-5625 2400)(-5625 2450);
WIRE 17 -1 (-5625 2350)(-5625 2400);
WIRE 17 -1 (-5625 2300)(-5625 2350);
WIRE 17 -1 (-5625 2250)(-5625 2300);
WIRE 17 -1 (-5625 2200)(-5625 2250);
WIRE 17 -1 (-5625 2150)(-5625 2200);
WIRE 17 -1 (-5625 2100)(-5625 2150);
WIRE 17 -1 (-5625 2050)(-5625 2100);
WIRE 17 -1 (-5625 2000)(-5625 2050);
WIRE 17 -1 (-5625 1950)(-5625 2000);
WIRE 17 -1 (-5625 1900)(-5625 1950);
WIRE 17 -1 (-5625 1850)(-5625 1900);
WIRE 17 -1 (-5625 1800)(-5625 1850);
WIRE 17 -1 (-5625 1750)(-5625 1800);
WIRE 17 -1 (-5625 1700)(-5625 1750);
WIRE 17 -1 (-5625 1650)(-5625 1700);
WIRE 17 -1 (-5625 1600)(-5625 1650);
WIRE 17 -1 (-5625 1550)(-5625 1600);
WIRE 17 -1 (-5625 800)(-5625 825);
WIRE 17 -1 (-5625 750)(-5625 800);
WIRE 17 -1 (-5625 825)(-6375 825);
FORCEPROP 2 LAST SIG_NAME M_K_CLK_DN<3:0>
J 0
(-6325 835);
DISPLAY 0.617021 (-6325 835);
PAINT ORANGE (-6325 835);
WIRE 17 -1 (-5625 700)(-5625 750);
WIRE 17 -1 (-5625 650)(-5625 700);
WIRE 17 -1 (-5625 1000)(-5625 1025);
WIRE 17 -1 (-5625 950)(-5625 1000);
WIRE 17 -1 (-5625 1025)(-6375 1025);
FORCEPROP 2 LAST SIG_NAME M_K_CLK_DP<3:0>
J 0
(-6325 1035);
DISPLAY 0.617021 (-6325 1035);
PAINT ORANGE (-6325 1035);
WIRE 17 -1 (-5625 900)(-5625 950);
WIRE 17 -1 (-5625 850)(-5625 900);
WIRE 17 -1 (-5625 1450)(-5625 1475);
WIRE 17 -1 (-5625 1400)(-5625 1450);
WIRE 17 -1 (-5625 1475)(-6375 1475);
FORCEPROP 2 LAST SIG_NAME M_K_ECC<7:0>
J 0
(-6325 1485);
DISPLAY 0.617021 (-6325 1485);
PAINT ORANGE (-6325 1485);
WIRE 17 -1 (-5625 1350)(-5625 1400);
WIRE 17 -1 (-5625 1300)(-5625 1350);
WIRE 17 -1 (-5625 1250)(-5625 1300);
WIRE 17 -1 (-5625 1200)(-5625 1250);
WIRE 17 -1 (-5625 1150)(-5625 1200);
WIRE 17 -1 (-5625 1100)(-5625 1150);
WIRE 16 -1 (-5025 525)(-6375 525);
FORCEPROP 2 LAST SIG_NAME M_K_C<2>
J 0
(-6325 535);
DISPLAY 0.617021 (-6325 535);
PAINT ORANGE (-6325 535);
WIRE 16 -1 (-5025 1075)(-5525 1075);
WIRE 16 -1 (-5025 1125)(-5525 1125);
WIRE 16 -1 (-5025 1175)(-5525 1175);
WIRE 16 -1 (-5025 1225)(-5525 1225);
WIRE 16 -1 (-5025 1275)(-5525 1275);
WIRE 16 -1 (-5025 1325)(-5525 1325);
WIRE 16 -1 (-5025 1375)(-5525 1375);
WIRE 16 -1 (-5025 1425)(-5525 1425);
WIRE 16 -1 (-5525 1525)(-5025 1525);
WIRE 16 -1 (-5525 1575)(-5025 1575);
WIRE 16 -1 (-5525 1625)(-5025 1625);
WIRE 16 -1 (-5025 1675)(-5525 1675);
WIRE 16 -1 (-5525 1725)(-5025 1725);
WIRE 16 -1 (-5525 1775)(-5025 1775);
WIRE 16 -1 (-5025 1825)(-5525 1825);
WIRE 16 -1 (-5525 1875)(-5025 1875);
WIRE 16 -1 (-5525 1925)(-5025 1925);
WIRE 16 -1 (-5525 1975)(-5025 1975);
WIRE 16 -1 (-5525 2025)(-5025 2025);
WIRE 16 -1 (-5025 825)(-5525 825);
WIRE 16 -1 (-5025 875)(-5525 875);
WIRE 16 -1 (-5025 925)(-5525 925);
WIRE 16 -1 (-5025 975)(-5525 975);
WIRE 16 -1 (-5025 625)(-5525 625);
WIRE 16 -1 (-5025 675)(-5525 675);
WIRE 16 -1 (-5025 725)(-5525 725);
WIRE 16 -1 (-5025 775)(-5525 775);
WIRE 16 -1 (-5525 2075)(-5025 2075);
WIRE 16 -1 (-5525 2125)(-5025 2125);
WIRE 16 -1 (-5525 2175)(-5025 2175);
WIRE 16 -1 (-5525 2225)(-5025 2225);
WIRE 16 -1 (-5025 2275)(-5525 2275);
WIRE 16 -1 (-5525 2325)(-5025 2325);
WIRE 16 -1 (-5525 2375)(-5025 2375);
WIRE 16 -1 (-5025 2425)(-5525 2425);
WIRE 16 -1 (-5525 2475)(-5025 2475);
WIRE 16 -1 (-5525 2525)(-5025 2525);
WIRE 16 -1 (-5525 2575)(-5025 2575);
WIRE 16 -1 (-5525 2625)(-5025 2625);
WIRE 16 -1 (-5025 2675)(-5525 2675);
WIRE 16 -1 (-5525 2725)(-5025 2725);
WIRE 16 -1 (-5525 2775)(-5025 2775);
WIRE 16 -1 (-5525 2825)(-5025 2825);
WIRE 16 -1 (-5525 2875)(-5025 2875);
WIRE 16 -1 (-5525 2925)(-5025 2925);
WIRE 16 -1 (-5525 2975)(-5025 2975);
WIRE 16 -1 (-5025 3025)(-5525 3025);
WIRE 16 -1 (-5525 3075)(-5025 3075);
WIRE 16 -1 (-5525 3125)(-5025 3125);
WIRE 16 -1 (-5525 3175)(-5025 3175);
WIRE 16 -1 (-5525 3225)(-5025 3225);
WIRE 16 -1 (-5525 3275)(-5025 3275);
WIRE 16 -1 (-5525 3325)(-5025 3325);
WIRE 16 -1 (-5025 3375)(-5525 3375);
WIRE 16 -1 (-5525 3425)(-5025 3425);
WIRE 16 -1 (-5525 3475)(-5025 3475);
WIRE 16 -1 (-5025 3525)(-5525 3525);
WIRE 16 -1 (-5525 3575)(-5025 3575);
WIRE 16 -1 (-5525 3625)(-5025 3625);
WIRE 16 -1 (-5025 3675)(-5525 3675);
WIRE 16 -1 (-5025 3725)(-5525 3725);
WIRE 16 -1 (-5025 3775)(-5525 3775);
WIRE 16 -1 (-5025 3825)(-5525 3825);
WIRE 16 -1 (-5025 3875)(-5525 3875);
WIRE 16 -1 (-5025 3925)(-5525 3925);
WIRE 16 -1 (-5025 3975)(-5525 3975);
WIRE 16 -1 (-5025 4025)(-5525 4025);
WIRE 16 -1 (-5025 4075)(-5525 4075);
WIRE 16 -1 (-5025 4125)(-5525 4125);
WIRE 16 -1 (-5025 4175)(-5525 4175);
WIRE 16 -1 (-5025 4225)(-5525 4225);
WIRE 16 -1 (-5025 4275)(-5525 4275);
WIRE 16 -1 (-5025 4325)(-5525 4325);
WIRE 16 -1 (-5025 4375)(-5525 4375);
WIRE 16 -1 (-5025 4425)(-5525 4425);
WIRE 16 -1 (-5025 4475)(-5525 4475);
WIRE 16 -1 (-5025 4525)(-5525 4525);
WIRE 16 -1 (-5025 4575)(-5525 4575);
WIRE 16 -1 (-5025 4625)(-5525 4625);
WIRE 16 -1 (-5025 4675)(-5525 4675);
WIRE 16 -1 (-3325 1425)(-2900 1425);
WIRE 16 -1 (-3325 1475)(-2900 1475);
WIRE 16 -1 (-3325 1525)(-2900 1525);
WIRE 16 -1 (-3325 1575)(-2900 1575);
WIRE 16 -1 (-3325 1925)(-2900 1925);
WIRE 16 -1 (-3325 1975)(-2900 1975);
WIRE 16 -1 (-3325 2025)(-2900 2025);
WIRE 16 -1 (-3325 975)(-2900 975);
WIRE 16 -1 (-3325 1025)(-2900 1025);
WIRE 16 -1 (-3325 1075)(-2900 1075);
WIRE 16 -1 (-3325 1125)(-2900 1125);
WIRE 16 -1 (-3325 1175)(-2900 1175);
WIRE 16 -1 (-3325 1225)(-2900 1225);
WIRE 16 -1 (-3325 1275)(-2900 1275);
WIRE 16 -1 (-3325 1325)(-2900 1325);
WIRE 16 -1 (-3325 1675)(-2900 1675);
WIRE 16 -1 (-3325 1725)(-2900 1725);
WIRE 16 -1 (-3325 1775)(-2900 1775);
WIRE 16 -1 (-3325 1825)(-2900 1825);
WIRE 16 -1 (-3325 825)(-2900 825);
WIRE 16 -1 (-3325 875)(-2900 875);
WIRE 16 -1 (-3325 725)(-2900 725);
WIRE 16 -1 (-3325 775)(-2900 775);
WIRE 16 -1 (-3325 525)(-2050 525);
FORCEPROP 2 LAST SIG_NAME M_K_PAR
J 0
(-2700 535);
DISPLAY 0.617021 (-2700 535);
PAINT ORANGE (-2700 535);
WIRE 16 -1 (-3325 575)(-2050 575);
FORCEPROP 2 LAST SIG_NAME M_K_ALERT_N
J 0
(-2700 585);
DISPLAY 0.617021 (-2700 585);
PAINT ORANGE (-2700 585);
WIRE 16 -1 (-3325 625)(-2050 625);
FORCEPROP 2 LAST SIG_NAME M_K_ACT_N
J 0
(-2700 635);
DISPLAY 0.617021 (-2700 635);
PAINT ORANGE (-2700 635);
WIRE 16 -1 (-3325 2075)(-2900 2075);
WIRE 16 -1 (-3325 2125)(-2900 2125);
WIRE 16 -1 (-3325 2175)(-2900 2175);
WIRE 16 -1 (-3325 2225)(-2900 2225);
WIRE 16 -1 (-3325 2275)(-2900 2275);
WIRE 16 -1 (-3325 2325)(-2900 2325);
WIRE 16 -1 (-3325 2375)(-2900 2375);
WIRE 16 -1 (-3325 2425)(-2900 2425);
WIRE 16 -1 (-3325 2475)(-2900 2475);
WIRE 16 -1 (-3325 2525)(-2900 2525);
WIRE 16 -1 (-3325 2575)(-2900 2575);
WIRE 16 -1 (-3325 2625)(-2900 2625);
WIRE 16 -1 (-3325 2675)(-2900 2675);
WIRE 16 -1 (-3325 2725)(-2900 2725);
WIRE 16 -1 (-3325 2775)(-2900 2775);
WIRE 16 -1 (-3325 3825)(-2900 3825);
WIRE 16 -1 (-3325 3875)(-2900 3875);
WIRE 16 -1 (-3325 3925)(-2900 3925);
WIRE 16 -1 (-3325 3975)(-2900 3975);
WIRE 16 -1 (-3325 4025)(-2900 4025);
WIRE 16 -1 (-3325 4075)(-2900 4075);
WIRE 16 -1 (-3325 2875)(-2900 2875);
WIRE 16 -1 (-3325 2925)(-2900 2925);
WIRE 16 -1 (-3325 2975)(-2900 2975);
WIRE 16 -1 (-3325 3025)(-2900 3025);
WIRE 16 -1 (-3325 3075)(-2900 3075);
WIRE 16 -1 (-3325 3125)(-2900 3125);
WIRE 16 -1 (-3325 3175)(-2900 3175);
WIRE 16 -1 (-3325 3225)(-2900 3225);
WIRE 16 -1 (-3325 3275)(-2900 3275);
WIRE 16 -1 (-3325 3325)(-2900 3325);
WIRE 16 -1 (-3325 3375)(-2900 3375);
WIRE 16 -1 (-3325 3425)(-2900 3425);
WIRE 16 -1 (-3325 3475)(-2900 3475);
WIRE 16 -1 (-3325 3525)(-2900 3525);
WIRE 16 -1 (-3325 3575)(-2900 3575);
WIRE 16 -1 (-3325 3625)(-2900 3625);
WIRE 16 -1 (-3325 3675)(-2900 3675);
WIRE 16 -1 (-3325 3725)(-2900 3725);
WIRE 16 -1 (-3325 4125)(-2900 4125);
WIRE 16 -1 (-3325 4175)(-2900 4175);
WIRE 16 -1 (-3325 4225)(-2900 4225);
WIRE 16 -1 (-3325 4275)(-2900 4275);
WIRE 16 -1 (-3325 4325)(-2900 4325);
WIRE 16 -1 (-3325 4375)(-2900 4375);
WIRE 16 -1 (-3325 4425)(-2900 4425);
WIRE 16 -1 (-3325 4475)(-2900 4475);
WIRE 16 -1 (-3325 4525)(-2900 4525);
WIRE 16 -1 (-3325 4575)(-2900 4575);
WIRE 16 -1 (-3325 4625)(-2900 4625);
WIRE 16 -1 (-3325 4675)(-2900 4675);
FORCENOTE
BOM_COST=PROC_SOCKET
(-7975 225) 0;
DISPLAY LEFT (-7975 225);
DISPLAY 1.723404 (-7975 225);
PAINT PURPLE (-7975 225);
FORCENOTE
ROOM=CPU1
(-7975 350) 0;
DISPLAY LEFT (-7975 350);
DISPLAY 1.723404 (-7975 350);
PAINT PURPLE (-7975 350);
QUIT
